# BARRELEYE_G2-FPDB_POST-PVT-X02-BOM-X05-20171123_Final.xls.xlsx — Changelist (bom)
| BOM Change List Date:Mon May 15 15:11:42 GMT+08:00 2017 |  |  |  |  |  |  |  |  |  |
| New BOM file : C:\<user>\BARRELEYE_G2-FPDB_POST-DVT-X01-BOM-X02-20170515.xls |  |  |  |  |  |  |  |  |  |
| Old BOM file : C:\<user>\BARRELEYE_G2-FPDB_POST-DVT-X01-BOM-X01-20170509.xls |  |  |  |  |  |  |  |  |  |
| ##### Add Parts |  |  |  |  |  |  |  |  |  |
| Item | Location | Qty | Foxconn P/N | Part Description | Manufacturer Full Name | Manufacturer P/N | RoHS | Sheet |  |
| 1 | PSUR2,PEUR2,PEUR7 | 3 | 610116G00-017-G | RES,150KOhm,+/-1%,1/16W,G,SMD0402 | KOA SPEER ELECTRONICS, INC. | RK73H1ETTP1503F | N | PWA BOM |  |
| 2 | PSUR4,PEUR6 | 2 | 610118S00-017-G | RES,54.9KOhm,+/-1%,1/16W,G,SMD0402 | KOA SPEER ELECTRONICS, INC. | RK73H1ETTP5492F | N | PWA BOM |  |
| 3 | PSUQ1 | 1 | 51030CQ00-185-G | MOS N,2N7002,60V,115mA,7.5ohm@5V,G,SOT23-3,SMD | FAIRCHILD SEMICONDUCTOR CORP | 2N7002 | N | PWA BOM |  |
|  |  |  | 510301N00-223-G | MOS N,2N7002LT1G,60V,0.115A,7.5ohm@5V,G,SOT23-3,SMD | ON SEMICONDUCTOR CORP | 2N7002LT1G | G | PWA BOM |  |
| 4 | PSUR5 | 1 | 61011N000-017-G | RES,68KOhm,+/-1%,1/16W,G,SMD0402 | KOA SPEER ELECTRONICS, INC. | RK73H1ETTP6802F | N | PWA BOM |  |
| 5 | PSUSW1,PEUSW1 | 2 | 34080F500-653-G | CONN,Switch,slide,25mA,24V,G,SMD-8 | DIPTRONICS MANUFACTURING INC. | DHN-04F-T-V-T/R |  | PWA BOM |  |
| ##### Remove Parts |  |  |  |  |  |  |  |  |  |
| Item | Location | Qty | Foxconn P/N | Part Description | Manufacturer Full Name | Manufacturer P/N | RoHS | Sheet |  |
| 1 | PEUQ2 | 1 | 51030CQ00-185-G | MOS N,2N7002,60V,115mA,7.5ohm@5V,G,SOT23-3,SMD | FAIRCHILD SEMICONDUCTOR CORP | 2N7002 | N | PWA BOM |  |
|  |  |  | 510301N00-223-G | MOS N,2N7002LT1G,60V,0.115A,7.5ohm@5V,G,SOT23-3,SMD | ON SEMICONDUCTOR CORP | 2N7002LT1G | G | PWA BOM |  |
| ##### Change Parts |  |  |  |  |  |  |  |  |  |
| Item | Location | Qty | Foxconn P/N | Part Description | Manufacturer Full Name | Manufacturer P/N | RoHS | Sheet | Remark |
| 1 | C1,C2,C3,PHAC5,C18,C19,C22,C35,C2111,C2112,C2113,C2114,C2115,C2116,C2171 | 15 | 620103700-015-G | CAP,100nF,+/-10%,X7R,10V,G,SMD0402 | MURATA ELEC. NORTH AMERICA | GRM155R71A104K | Y | PWA BOM | In New BOM |
|  |  |  | 620103700-012-G | CAP,0.1uF,+/-10%,X7R,10V,G,SMD0402 | WALSIN TECHNOLOGY CORPORATION | 0402B104K100CT | G | PWA BOM | In New BOM |
|  |  |  | 620103700-023-G | CAP,100nF,+/-10%,X7R,10V,G,SMD0402 | TAIYO ELECTRIC IND.CO.LTD | LMK105B7104KV-F | G | PWA BOM | In New BOM |
|  |  |  | 620103700-026-G | CAP,100nF,+/-10%,X7R,10V,G,SMD0402 | SAMSUNG SEMICONDUCTOR | CL05B104KP5NNNC | G | PWA BOM | In New BOM |
|  | C1,C2,C3,PHAC5,C18,C19,C22,C35,C2111,C2112,C2113,C2114,C2115,C2116,C2171 | 15 | 620103700-015-G | CAP,100nF,+/-10%,X7R,10V,G,SMD0402 | MURATA ELEC. NORTH AMERICA | GRM155R71A104K | Y | PWA BOM | In Old BOM |
|  |  |  | 620103700-012-G | CAP,0.1uF,+/-10%,X7R,10V,G,SMD0402 | WALSIN | 0402B104K100CT | G | PWA BOM | In Old BOM |
|  |  |  | 620103700-023-G | CAP,100nF,+/-10%,X7R,10V,G,SMD0402 | TAIYO | LMK105B7104KV-F | G | PWA BOM | In Old BOM |
|  |  |  | 620103700-026-G | CAP,100nF,+/-10%,X7R,10V,G,SMD0402 | SAMSUNG | CL05B104KP5NNNC | G | PWA BOM | In Old BOM |
| 2 | C4,C11 | 2 | 62010BN00-015-G | CAP,1uF,+/-10%,X5R,6.3V,G,SMD0402 | MURATA ELEC. NORTH AMERICA | GRM155R60J105K | Y | PWA BOM | In New BOM |
|  |  |  | 62010BN00-023-G | CAP,1uF,+/-10%,X5R,6.3V,G,SMD0402 | TAIYO ELECTRIC IND.CO.LTD | JMK105BJ105KV | G | PWA BOM | In New BOM |
|  |  |  | 62010BN00-026-G | CAP,1uF,+/-10%,X5R,6.3V,G,SMD0402 | SAMSUNG SEMICONDUCTOR | CL05A105KQ5NNNC | G | PWA BOM | In New BOM |
|  |  |  | 62010BN00-011-G | CAP,1uF,+/-10%,X5R,6.3V,G,SMD0402 | YAGEO CORPORATION COMPONENT | CC0402KRX5R5BB105 |  | PWA BOM | In New BOM |
|  |  |  | 62010BN00-012-G | CAP,1uF,+/-10%,X5R,6.3V,G,SMD0402 | WALSIN TECHNOLOGY CORPORATION | 0402X105K6R3CT |  | PWA BOM | In New BOM |
|  | C4,C11 | 2 | 62010BN00-015-G | CAP,1uF,+/-10%,X5R,6.3V,G,SMD0402 | MURATA ELEC. NORTH AMERICA | GRM155R60J105K | Y | PWA BOM | In Old BOM |
|  |  |  | 62010BN00-023-G | CAP,1uF,+/-10%,X5R,6.3V,G,SMD0402 | TAIYO ELECTRIC IND.CO.LTD | JMK105BJ105KV | G | PWA BOM | In Old BOM |
|  |  |  | 62010BN00-026-G | CAP,1uF,+/-10%,X5R,6.3V,G,SMD0402 | SAMSUNG | CL05A105KQ5NNNC | G | PWA BOM | In Old BOM |
|  |  |  | 62010BN00-011-G | CAP,1uF,+/-10%,X5R,6.3V,G,SMD0402 | YAGEO CORPORATION COMPONENT | CC0402KRX5R5BB105 |  | PWA BOM | In Old BOM |
|  |  |  | 62010BN00-012-G | CAP,1uF,+/-10%,X5R,6.3V,G,SMD0402 | WALSIN TECHNOLOGY CORPORATION | 0402X105K6R3CT |  | PWA BOM | In Old BOM |
| 3 | C5,C12 | 2 | 620106200-015-G | CAP,10nF,+/-10%,X7R,16V,G,SMD0402 | MURATA ELEC. NORTH AMERICA | GRM155R71C103K | N | PWA BOM | In New BOM |
|  |  |  | 620106200-012-G | CAP,10nF,+/-10%,X7R,16V,G,SMD0402 | WALSIN TECHNOLOGY CORPORATION | 0402B103K160CT | G | PWA BOM | In New BOM |
|  |  |  | 620106200-026-G | CAP,10nF,+/-10%,X7R,16V,G,SMD0402 | SAMSUNG SEMICONDUCTOR | CL05B103KO5NNNC | G | PWA BOM | In New BOM |
|  |  |  | 620106200-023-G | CAP,10nF,+/-10%,X7R,16V,G,SMD0402 | TAIYO ELECTRIC IND.CO.LTD | EMK105B7103KV-F | G | PWA BOM | In New BOM |
|  | C5,C12 | 2 | 620106200-015-G | CAP,10nF,+/-10%,X7R,16V,G,SMD0402 | MURATA ELEC. NORTH AMERICA | GRM155R71C103K | N | PWA BOM | In Old BOM |
|  |  |  | 620106200-012-G | CAP,10nF,+/-10%,X7R,16V,G,SMD0402 | WALSIN | 0402B103K160CT | G | PWA BOM | In Old BOM |
|  |  |  | 620106200-026-G | CAP,10nF,+/-10%,X7R,16V,G,SMD0402 | SAMSUNG | CL05B103KO5NNNC | G | PWA BOM | In Old BOM |
|  |  |  | 620106200-023-G | CAP,10nF,+/-10%,X7R,16V,G,SMD0402 | TAIYO | EMK105B7103KV-F | G | PWA BOM | In Old BOM |
| 4 | C6,C7,C9,PSRC10,C13,C14,C16,C20,C21,C38,C39,C46,C362,C394,C2107,C2108,C2109 | 17 | 620101T02-015-G | CAP,100nF,+/-10%,X7R,16V,G,SMD0402 | MURATA ELEC. NORTH AMERICA | GRM155R71C104K | Y | PWA BOM | In New BOM |
|  |  |  | 620101T00-012-G | CAP,100nF,+/-10%,X7R,16V,G,SMD0402 | WALSIN TECHNOLOGY CORPORATION | 0402B104K160CT | G | PWA BOM | In New BOM |
|  |  |  | 620101T00-026-G | CAP,100nF,+/-10%,X7R,16V,G,SMD0402 | SAMSUNG SEMICONDUCTOR | CL05B104KO5NNNC | G | PWA BOM | In New BOM |
|  |  |  | 620101T00-015-G | CAP,100nF,+/-10%,X7R,16V,G,SMD0402 | MURATA ELEC. NORTH AMERICA | GRM155R71C104KA88D | G | PWA BOM | In New BOM |
|  | C6,C7,C9,PSRC10,C13,C14,C16,C20,C21,C38,C39,C46,C362,C394,C2107,C2108,C2109 | 17 | 620101T02-015-G | CAP,100nF,+/-10%,X7R,16V,G,SMD0402 | MURATA ELEC. NORTH AMERICA | GRM155R71C104K | Y | PWA BOM | In Old BOM |
|  |  |  | 620101T00-012-G | CAP,100nF,+/-10%,X7R,16V,G,SMD0402 | WALSIN | 0402B104K160CT | G | PWA BOM | In Old BOM |
|  |  |  | 620101T00-026-G | CAP,100nF,+/-10%,X7R,16V,G,SMD0402 | SAMSUNG | CL05B104KO5NNNC | G | PWA BOM | In Old BOM |
|  |  |  | 620101T00-015-G | CAP,100nF,+/-10%,X7R,16V,G,SMD0402 | MURATA | GRM155R71C104KA88D | G | PWA BOM | In Old BOM |
| 5 | C8,C10,C15,C17,C40,C43,C47,C50,C53,C56 | 10 | 620130V00-015-G | CAP,10uF,+/-20%,X6S,16V,G,SMD0603 | MURATA ELEC. NORTH AMERICA | GRM188C81C106MA73D |  | PWA BOM | In New BOM |
|  |  |  | 620130V00-023-G | CAP,10uF,+/-20%,X6S,16V,G,SMD0603 | TAIYO ELECTRIC IND.CO.LTD | EMK107BC6106MA-T | G | PWA BOM | In New BOM |
|  | C8,C10,C15,C17,C40,C43,C47,C50,C53,C56 | 10 | 620130V00-015-G | CAP,10uF,+/-20%,X6S,16V,G,SMD0603 | MURATA ELEC. NORTH AMERICA | GRM188C81C106MA73D |  | PWA BOM | In Old BOM |
|  |  |  | 620130V00-023-G | CAP,10uF,+/-20%,X6S,16V,G,SMD0603 | TAIYO | EMK107BC6106MA-T | G | PWA BOM | In Old BOM |
| 6 | PHAC2,C36,C37 | 3 | 620103K00-015-G | CAP,1nF,+/-10%,X7R,50V,G,SMD0402 | MURATA ELEC. NORTH AMERICA | GRM155R71H102K | N | PWA BOM | In New BOM |
|  |  |  | 620103K00-012-G | CAP,1nF,+/-10%,X7R,50V,G,SMD0402 | WALSIN TECHNOLOGY CORPORATION | 0402B102K500CT | G | PWA BOM | In New BOM |
|  |  |  | 620103K00-026-G | CAP,1nF,+/-10%,X7R,50V,G,SMD0402 | SAMSUNG SEMICONDUCTOR | CL05B102KB5NNNC | G | PWA BOM | In New BOM |
|  |  |  | 620103K00-023-G | CAP,1nF,+/-10%,X7R,50V,G,SMD0402 | TAIYO ELECTRIC IND.CO.LTD | UMK105B7102KV-F | G | PWA BOM | In New BOM |
|  | PHAC2,C36,C37 | 3 | 620103K00-015-G | CAP,1nF,+/-10%,X7R,50V,G,SMD0402 | MURATA ELEC. NORTH AMERICA | GRM155R71H102K | N | PWA BOM | In Old BOM |
|  |  |  | 620103K00-012-G | CAP,1nF,+/-10%,X7R,50V,G,SMD0402 | WALSIN | 0402B102K500CT | G | PWA BOM | In Old BOM |
|  |  |  | 620103K00-026-G | CAP,1nF,+/-10%,X7R,50V,G,SMD0402 | SAMSUNG | CL05B102KB5NNNC | G | PWA BOM | In Old BOM |
|  |  |  | 620103K00-023-G | CAP,1nF,+/-10%,X7R,50V,G,SMD0402 | TAIYO | UMK105B7102KV-F | G | PWA BOM | In Old BOM |
| 7 | C41,C42,C44,C45,C48,C49,C51,C52,C54,C55,C57,C58 | 12 | 620100L00-015-G | CAP,22pF,+/-5%,NPO(C0G),50V,G,SMD0402 | MURATA ELEC. NORTH AMERICA | GRM1555C1H220J | Y | PWA BOM | In New BOM |
|  |  |  | 620100L08-012-G | CAP,22pF,+/-5%,NPO(C0G),50V,G,SMD0402 | WALSIN TECHNOLOGY CORPORATION | 0402N220J500CT | G | PWA BOM | In New BOM |
|  |  |  | 620100L00-026-G | CAP,22pF,+/-5%,NPO(C0G),50V,G,SMD0402 | SAMSUNG SEMICONDUCTOR | CL05C220JB5NNNC | G | PWA BOM | In New BOM |
|  |  |  | 620100L00-023-G | CAP,22pF,+/-5%,NPO(C0G),50V,G,SMD0402 | TAIYO ELECTRIC IND.CO.LTD | UMK105CG220JV-F | G | PWA BOM | In New BOM |
|  | C41,C42,C44,C45,C48,C49,C51,C52,C54,C55,C57,C58 | 12 | 620100L00-015-G | CAP,22pF,+/-5%,NPO(C0G),50V,G,SMD0402 | MURATA ELEC. NORTH AMERICA | GRM1555C1H220J | Y | PWA BOM | In Old BOM |
|  |  |  | 620100L08-012-G | CAP,22pF,+/-5%,NPO(C0G),50V,G,SMD0402 | WALSIN | 0402N220J500CT | G | PWA BOM | In Old BOM |
|  |  |  | 620100L00-026-G | CAP,22pF,+/-5%,NPO(C0G),50V,G,SMD0402 | SAMSUNG | CL05C220JB5NNNC | G | PWA BOM | In Old BOM |
|  |  |  | 620100L00-023-G | CAP,22pF,+/-5%,NPO(C0G),50V,G,SMD0402 | TAIYO | UMK105CG220JV-F | G | PWA BOM | In Old BOM |
| 8 | C398,C399 | 2 | 62012FR00-015-G | CAP,10uF,+/-20%,X5R,25V,G,SMD0603 | MURATA ELEC. NORTH AMERICA | GRM188R61E106M |  | PWA BOM | In New BOM |
|  |  |  | 62012FR00-023-G | CAP,10uF,+/-20%,X5R,25V,G,SMD0603 | TAIYO ELECTRIC IND.CO.LTD | TMK107BBJ106MA-T | G | PWA BOM | In New BOM |
|  |  |  | 62012FR00-026-G | CAP,10uF,+/-20%,X5R,25V,G,SMD0603 | SAMSUNG SEMICONDUCTOR | CL10A106MA8NRNC | G | PWA BOM | In New BOM |
|  | C398,C399 | 2 | 62012FR00-015-G | CAP,10uF,+/-20%,X5R,25V,G,SMD0603 | MURATA ELEC. NORTH AMERICA | GRM188R61E106M |  | PWA BOM | In Old BOM |
|  |  |  | 62012FR00-023-G | CAP,10uF,+/-20%,X5R,25V,G,SMD0603 | TAIYO | TMK107BBJ106MA-T | G | PWA BOM | In Old BOM |
|  |  |  | 62012FR00-026-G | CAP,10uF,+/-20%,X5R,25V,G,SMD0603 | SAMSUNG | CL10A106MA8NRNC | G | PWA BOM | In Old BOM |
| 9 | C400 | 1 | 620100D00-015-G | CAP,100nF,+/-10%,X7R,16V,G,SMD0603 | MURATA ELEC. NORTH AMERICA | GRM188R71C104K | N | PWA BOM | In New BOM |
|  |  |  | 620100D00-012-G | CAP,100nF,+/-10%,X7R,16V,G,SMD0603 | WALSIN TECHNOLOGY CORPORATION | 0603B104K160CT | G | PWA BOM | In New BOM |
|  |  |  | 620100D00-026-G | CAP,100nF,+/-10%,X7R,16V,G,SMD0603 | SAMSUNG SEMICONDUCTOR | CL10B104KO8NNNC | G | PWA BOM | In New BOM |
|  | C400 | 1 | 620100D00-015-G | CAP,100nF,+/-10%,X7R,16V,G,SMD0603 | MURATA ELEC. NORTH AMERICA | GRM188R71C104K | N | PWA BOM | In Old BOM |
|  |  |  | 620100D00-012-G | CAP,100nF,+/-10%,X7R,16V,G,SMD0603 | WALSIN | 0603B104K160CT | G | PWA BOM | In Old BOM |
|  |  |  | 620100D00-026-G | CAP,100nF,+/-10%,X7R,16V,G,SMD0603 | SAMSUNG | CL10B104KO8NNNC | G | PWA BOM | In Old BOM |
| 10 | PSRC1,PSUC3,PEUC3,PSRC6,PHAC19,C2117 | 6 | 62012A400-015-G | CAP,100nF,+/-10%,X7R,25V,G,SMD0402 | MURATA ELEC. NORTH AMERICA | GRM155R71E104KE14D | N | PWA BOM | In New BOM |
|  |  |  | 62012A400-023-G | CAP,100nF,+/-10%,X7R,25V,G,SMD0402 | TAIYO ELECTRIC IND.CO.LTD | TMK105B7104KV-FR | G | PWA BOM | In New BOM |
|  |  |  | 62012A400-026-G | CAP,100nF,+/-10%,X7R,25V,G,SMD0402 | SAMSUNG SEMICONDUCTOR | CL05B104KA5NNNC | G | PWA BOM | In New BOM |
|  |  |  | 62012A400-012-G | CAP,100nF,+/-10%,X7R,25V,G,SMD0402 | WALSIN TECHNOLOGY CORPORATION | 0402B104K250CT | G | PWA BOM | In New BOM |
|  | PSRC1,PSUC3,PEUC3,PSRC6,PHAC19,C2117 | 6 | 62012A400-015-G | CAP,100nF,+/-10%,X7R,25V,G,SMD0402 | MURATA ELEC. NORTH AMERICA | GRM155R71E104KE14D | N | PWA BOM | In Old BOM |
|  |  |  | 62012A400-023-G | CAP,100nF,+/-10%,X7R,25V,G,SMD0402 | TAIYO | TMK105B7104KV-FR | G | PWA BOM | In Old BOM |
|  |  |  | 62012A400-026-G | CAP,100nF,+/-10%,X7R,25V,G,SMD0402 | SAMSUNG | CL05B104KA5NNNC | G | PWA BOM | In Old BOM |
|  |  |  | 62012A400-012-G | CAP,100nF,+/-10%,X7R,25V,G,SMD0402 | WALSIN | 0402B104K250CT | G | PWA BOM | In Old BOM |
| 11 | PHAC14,C2118 | 2 | 62010VD00-015-G | CAP,100nF,+/-10%,X7R,100V,G,SMD0603 | MURATA ELEC. NORTH AMERICA | GRM188R72A104K |  | PWA BOM | In New BOM |
|  |  |  | 62010VD00-026-G | CAP,100nF,+/-10%,X7R,100V,G,SMD0603 | SAMSUNG SEMICONDUCTOR | CL10B104KC8NNNC | G | PWA BOM | In New BOM |
|  | PHAC14,C2118 | 2 | 62010VD00-015-G | CAP,100nF,+/-10%,X7R,100V,G,SMD0603 | MURATA ELEC. NORTH AMERICA | GRM188R72A104K |  | PWA BOM | In Old BOM |
|  |  |  | 62010VD00-026-G | CAP,100nF,+/-10%,X7R,100V,G,SMD0603 | SAMSUNG | CL10B104KC8NNNC | G | PWA BOM | In Old BOM |
| 12 | C2168 | 1 | 620108000-015-G | CAP,100pF,+/-5%,NPO(C0G),50V,G,SMD0402 | MURATA ELEC. NORTH AMERICA | GRM1555C1H101J | Y | PWA BOM | In New BOM |
|  |  |  | 62010800A-012-G | CAP,100pF,+/-5%,NPO(C0G),50V,G,SMD0402 | WALSIN TECHNOLOGY CORPORATION | 0402N101J500CT |  | PWA BOM | In New BOM |
|  |  |  | 620108000-026-G | CAP,100pF,+/-5%,NPO(C0G),50V,G,SMD0402 | SAMSUNG SEMICONDUCTOR | CL05C101JB5NNNC |  | PWA BOM | In New BOM |
|  |  |  | 620108000-023-G | CAP,100pF,+/-5%,NPO(C0G),50V,G,SMD0402 | TAIYO ELECTRIC IND.CO.LTD | UMK105CG101JV-F |  | PWA BOM | In New BOM |
|  | C2168 | 1 | 620108000-015-G | CAP,100pF,+/-5%,NPO(C0G),50V,G,SMD0402 | MURATA ELEC. NORTH AMERICA | GRM1555C1H101J | Y | PWA BOM | In Old BOM |
|  |  |  | 62010800A-012-G | CAP,100pF,+/-5%,NPO(C0G),50V,G,SMD0402 | WALSIN | 0402N101J500CT |  | PWA BOM | In Old BOM |
|  |  |  | 620108000-026-G | CAP,100pF,+/-5%,NPO(C0G),50V,G,SMD0402 | SAMSUNG SEMICONDUCTOR | CL05C101JB5NNNC |  | PWA BOM | In Old BOM |
|  |  |  | 620108000-023-G | CAP,100pF,+/-5%,NPO(C0G),50V,G,SMD0402 | TAIYO ELECTRIC IND.CO.LTD | UMK105CG101JV-F |  | PWA BOM | In Old BOM |
| 13 | D33 | 1 | 520308D00-237-G | DIODE,Schottky Rectifier,1N5819HW-7-F,40V,1A,G,SOD123-2,SMD | DIODES INCORPORATION | 1N5819HW-7-F | N | PWA BOM | In New BOM |
|  |  |  | 520318S00-223-G | Diode,Schottky,MBR140SFT3G,40V,1A,G,SOD-123FL-2,SMD | ON SEMICONDUCTOR CORP | MBR140SFT3G | G | PWA BOM | In New BOM |
|  |  |  | 52030P100-223-G | Diode,Schottky,MBR140SFT1G,40V,1A,SOD-123FL,2P,G | ON SEMICONDUCTOR CORP | MBR140SFT1G | G | PWA BOM | In New BOM |
|  | D33 | 1 | 520308D00-237-G | DIODE,Schottky Rectifier,1N5819HW-7-F,40V,1A,G,SOD123-2,SMD | DIODES INCORPORATION | 1N5819HW-7-F | N | PWA BOM | In Old BOM |
|  |  |  | 520318S00-223-G | Diode,Schottky,MBR140SFT3G,40V,1A,G,SOD-123FL-2,SMD | ON SEMICONDUCTOR CORP | MBR140SFT3G | G | PWA BOM | In Old BOM |
|  |  |  | 52030P100-223-G | Diode,Schottky,MBR140SFT1G,40V,1A,SOD-123FL,2P,G | ON | MBR140SFT1G | G | PWA BOM | In Old BOM |
| 14 | FS4,FS5,FS6,FS7,FS8,FS9 | 6 | 730103M00-086-G | Fuse,Fast acting,32V,5A,G,SMD0603 | LITTELFUSE FAR EAST PTE LTD | 0438005.WR | Y | PWA BOM | In New BOM |
|  |  |  | 730103M00-088-G | Fuse,Fast acting,32V,5A,SMD0603,G | COOPER BUSSMANN, INC. | CC06H5A-TR | G | PWA BOM | In New BOM |
|  | FS4,FS5,FS6,FS7,FS8,FS9 | 6 | 730103M00-086-G | Fuse,Fast acting,32V,5A,G,SMD0603 | LITTELFUSE FAR EAST PTE LTD | 0438005.WR | Y | PWA BOM | In Old BOM |
|  |  |  | 730100H00-085-G | Fuse,Very fast acting,32V,5A,G,SMD0603 | BEL FUSE INC | C2Q 5TR | G | PWA BOM | In Old BOM |
|  |  |  | 730103M00-088-G | Fuse,Fast acting,32V,5A,SMD0603,G | COOPER BUSSMANN, INC. | CC06H5A-TR | G | PWA BOM | In Old BOM |
| 15 | PSUC1,PEUC1,PSUC2,PEUC2 | 4 | 62011J601-015-G | CAP,2.2uF,+/-10%,X7R,100V,G,SMD1210 | MURATA ELEC. NORTH AMERICA | GRM32ER72A225K |  | PWA BOM | In New BOM |
|  |  |  | 62011J600-026-G | CAP,2.2uF,+/-10%,X7R,100V,G,SMD1210 | SAMSUNG SEMICONDUCTOR | CL32B225KCJSNNE | G | PWA BOM | In New BOM |
|  | PSUC1,PEUC1,PSUC2,PEUC2 | 4 | 62011J601-015-G | CAP,2.2uF,+/-10%,X7R,100V,G,SMD1210 | MURATA ELEC. NORTH AMERICA | GRM32ER72A225K |  | PWA BOM | In Old BOM |
|  |  |  | 62011J600-026-G | CAP,2.2uF,+/-10%,X7R,100V,G,SMD1210 | SAMSUNG | CL32B225KCJSNNE | G | PWA BOM | In Old BOM |
| 16 | PSUC4,PEUC4 | 2 | 62011F100-015-G | CAP,1uF,+/-10%,X7R,25V,G,SMD0603 | MURATA ELEC. NORTH AMERICA | GRM188R71E105K | N | PWA BOM | In New BOM |
|  |  |  | 62011F100-023-G | CAP,1uF,+/-10%,X7R,25V,G,SMD0603 | TAIYO ELECTRIC IND.CO.LTD | TMK107B7105KA-T | G | PWA BOM | In New BOM |
|  |  |  | 62011F100-026-G | CAP,1uF,+/-10%,X7R,25V,G,SMD0603 | SAMSUNG SEMICONDUCTOR | CL10B105KA8NNNC | G | PWA BOM | In New BOM |
|  | PSUC4,PEUC4 | 2 | 62011F100-015-G | CAP,1uF,+/-10%,X7R,25V,G,SMD0603 | MURATA ELEC. NORTH AMERICA | GRM188R71E105K | N | PWA BOM | In Old BOM |
|  |  |  | 62011F100-023-G | CAP,1uF,+/-10%,X7R,25V,G,SMD0603 | TAIYO | TMK107B7105KA-T | G | PWA BOM | In Old BOM |
|  |  |  | 62011F100-026-G | CAP,1uF,+/-10%,X7R,25V,G,SMD0603 | SAMSUNG | CL10B105KA8NNNC | G | PWA BOM | In Old BOM |
| 17 | R1,PEUR4,PSRR8,R9,PSRR9,R10,PHAR11,PHAR12,PSRR15,PSRR18,PHAR24,PHAR25,R30,R31,PHAR31,PHAR32,PHAR34,R51,R52,R56,R57,R70,R71,R84,R85,R123,R135,R139,R140,R161,R171,R199,R235,R494,R499,PSUR500,PEUR500,PSUR501,PEUR501,R1478,R1491,R1775,R1780,R1782,R1784,R1785,R1786,R1787,R1788,R1789,R1790,R1791,R1792,R1793,R1794,R1795,R1796,R1797,R1798,R1799,R1800,R1801,R1802,R1813,PHAR33 | 65 | 610107A00-017-G | RES,0 Ohm,+/-5%,1/16W,G,SMD0402 | KOA SPEER ELECTRONICS, INC. | RK73Z1ETTP | N | PWA BOM | In New BOM |
|  |  |  | 610107A00-012-G | RES,0 Ohm,+/-5%,1/16W,G,SMD0402 | WALSIN TECHNOLOGY CORPORATION | WR04X000PTL | G | PWA BOM | In New BOM |
|  |  |  | 610107A00-011-G | RES,0 Ohm,+/-5%,1/16W,G,SMD0402 | YAGEO CORPORATION COMPONENT | RC0402JR-070RL | G | PWA BOM | In New BOM |
|  |  |  | 610107A00-044-G | RES,0 Ohm,+/-5%,1/16W,G,SMD0402 | TA-I TECHNOLOGY CO., LTD. | RM04JTN0 | G | PWA BOM | In New BOM |
|  |  |  | 610107A00-024-G | RES,0 Ohm,+/-5%,1/16W,G,SMD0402 | PANASONIC INDUSTRIAL CO.,LTD. | ERJ2GE0R00X | G | PWA BOM | In New BOM |
|  |  |  | 610107A00-029-G | RES,0 Ohm,+/-5%,1/16W,G,SMD0402 | VISHAY ENTER TECHNO LOGY.INC | CRCW04020000Z0ED | G | PWA BOM | In New BOM |
|  | R1,PEUR4,PSRR8,R9,PSRR9,R10,PHAR11,PHAR12,PSRR15,PSRR18,PHAR24,PHAR25,R30,R31,PHAR31,PHAR32,PHAR34,R51,R52,R56,R57,R70,R71,R84,R85,R123,R135,R139,R140,R161,R171,R199,R235,R494,R499,PSUR500,PEUR500,PSUR501,PEUR501,R1478,R1491,R1775,R1780,R1782,R1784,R1785,R1786,R1787,R1788,R1789,R1790,R1791,R1792,R1793,R1794,R1795,R1796,R1797,R1798,R1799,R1800,R1801,R1802,R1813,PHAR33 | 65 | 610107A00-017-G | RES,0 Ohm,+/-5%,1/16W,G,SMD0402 | KOA SPEER ELECTRONICS, INC. | RK73Z1ETTP | N | PWA BOM | In Old BOM |
|  |  |  | 610107A00-012-G | RES,0 Ohm,+/-5%,1/16W,G,SMD0402 | WALSIN | WR04X000PTL | G | PWA BOM | In Old BOM |
|  |  |  | 610107A00-011-G | RES,0 Ohm,+/-5%,1/16W,G,SMD0402 | YAGEO | RC0402JR-070RL | G | PWA BOM | In Old BOM |
|  |  |  | 610107A00-044-G | RES,0 Ohm,+/-5%,1/16W,G,SMD0402 | TA-I | RM04JTN0 | G | PWA BOM | In Old BOM |
|  |  |  | 610107A00-024-G | RES,0 Ohm,+/-5%,1/16W,G,SMD0402 | PANASONIC | ERJ2GE0R00X | G | PWA BOM | In Old BOM |
|  |  |  | 610107A00-029-G | RES,0 Ohm,+/-5%,1/16W,G,SMD0402 | VISHAY | CRCW04020000Z0ED | G | PWA BOM | In Old BOM |
| 18 | PHAC1,PHAC7 | 2 | 620131D00-015-G | CAP,1uF,+/-10%,X6S,16V,G,SMD0402 | MURATA ELEC. NORTH AMERICA | GRM155C81C105KE11J |  | PWA BOM | In New BOM |
|  |  |  | 620131D00-023-G | CAP,1uF,+/-10%,X6S,16V,G,SMD0402 | TAIYO ELECTRIC IND.CO.LTD | EMK105C6105KV-F | G | PWA BOM | In New BOM |
|  | PHAC1,PHAC7 | 2 | 620131D00-015-G | CAP,1uF,+/-10%,X6S,16V,G,SMD0402 | MURATA ELEC. NORTH AMERICA | GRM155C81C105KE11J |  | PWA BOM | In Old BOM |
|  |  |  | 620131D00-023-G | CAP,1uF,+/-10%,X6S,16V,G,SMD0402 | TAIYO | EMK105C6105KV-F | G | PWA BOM | In Old BOM |
| 19 | PHAC3 | 1 | 620133600-015-G | CAP,1nF,+/-5%,X7R,100V,G,SMD0805 | MURATA ELEC. NORTH AMERICA | GRM219R72A102JA01D |  | PWA BOM | In New BOM |
|  |  |  | 620133600-012-G | CAP,1nF,+/-5%,X7R,100V,G,SMD0805 | WALSIN TECHNOLOGY CORPORATION | 0805B102J101CT | G | PWA BOM | In New BOM |
|  | PHAC3 | 1 | 620133600-015-G | CAP,1nF,+/-5%,X7R,100V,G,SMD0805 | MURATA ELEC. NORTH AMERICA | GRM219R72A102JA01D |  | PWA BOM | In Old BOM |
|  |  |  | 620133600-012-G | CAP,1nF,+/-5%,X7R,100V,G,SMD0805 | WALSIN | 0805B102J101CT | G | PWA BOM | In Old BOM |
| 20 | PHAC4 | 1 | 62010G800-015-G | CAP,22nF,+/-10%,X7R,16V,G,SMD0402 | MURATA ELEC. NORTH AMERICA | GRM155R71C223K | N | PWA BOM | In New BOM |
|  |  |  | 62010G800-012-G | CAP,22nF,+/-10%,X7R,16V,G,SMD0402 | WALSIN TECHNOLOGY CORPORATION | 0402B223K160CT | G | PWA BOM | In New BOM |
|  |  |  | 62010G800-026-G | CAP,22nF,+/-10%,X7R,16V,G,SMD0402 | SAMSUNG SEMICONDUCTOR | CL05B223KO5NNNC | G | PWA BOM | In New BOM |
|  |  |  | 62010G800-023-G | CAP,22nF,+/-10%,X7R,16V,G,SMD0402 | TAIYO ELECTRIC IND.CO.LTD | EMK105B7223KV-F | G | PWA BOM | In New BOM |
|  | PHAC4 | 1 | 62010G800-015-G | CAP,22nF,+/-10%,X7R,16V,G,SMD0402 | MURATA ELEC. NORTH AMERICA | GRM155R71C223K | N | PWA BOM | In Old BOM |
|  |  |  | 62010G800-012-G | CAP,22nF,+/-10%,X7R,16V,G,SMD0402 | WALSIN | 0402B223K160CT | G | PWA BOM | In Old BOM |
|  |  |  | 62010G800-026-G | CAP,22nF,+/-10%,X7R,16V,G,SMD0402 | SAMSUNG | CL05B223KO5NNNC | G | PWA BOM | In Old BOM |
|  |  |  | 62010G800-023-G | CAP,22nF,+/-10%,X7R,16V,G,SMD0402 | TAIYO | EMK105B7223KV-F | G | PWA BOM | In Old BOM |
| 21 | PHAC18 | 1 | 620135500-015-G | CAP,39nF,+/-10%,X7R,100V,G,SMD0805 | MURATA ELEC. NORTH AMERICA | GRM21BR72A393KA01L |  | PWA BOM | In New BOM |
|  |  |  | 620135500-012-G | CAP,39nF,+/-10%,X7R,100V,G,SMD0805 | WALSIN TECHNOLOGY CORPORATION | 0805B393K101CT | G | PWA BOM | In New BOM |
|  | PHAC18 | 1 | 620135500-015-G | CAP,39nF,+/-10%,X7R,100V,G,SMD0805 | MURATA ELEC. NORTH AMERICA | GRM21BR72A393KA01L |  | PWA BOM | In Old BOM |
|  |  |  | 620135500-012-G | CAP,39nF,+/-10%,X7R,100V,G,SMD0805 | WALSIN | 0805B393K101CT | G | PWA BOM | In Old BOM |
| 22 | PHAD3 | 1 | 52040EC00-237-G | DIODE,Zener,MMSZ5246B-7-F,16V,7.8mA,G,SOD123-2,SMD | DIODES INCORPORATION | MMSZ5246B-7-F | N | PWA BOM | In New BOM |
|  |  |  | 52040B500-223-G | DIODE,Zener,MMSZ5246BT1G,16V,7.8mA,G,SOD123-2,SMD | ON SEMICONDUCTOR CORP | MMSZ5246BT1G |  | PWA BOM | In New BOM |
|  |  |  | 52040EY00-031-G | Diode,ZENER,BZT52H-C16,17.1V,5mA,G,SOD123F-2,SMD | NXP SEMICONDUCTORS | BZT52H-C16 |  | PWA BOM | In New BOM |
|  | PHAD3 | 1 | 52040EC00-237-G | DIODE,Zener,MMSZ5246B-7-F,16V,7.8mA,G,SOD123-2,SMD | DIODES INEORPORATION | MMSZ5246B-7-F | N | PWA BOM | In Old BOM |
|  |  |  | 52040B500-223-G | DIODE,Zener,MMSZ5246BT1G,16V,7.8mA,G,SOD123-2,SMD | ON | MMSZ5246BT1G |  | PWA BOM | In Old BOM |
|  |  |  | 52040EY00-031-G | Diode,ZENER,BZT52H-C16,17.1V,5mA,G,SOD123F-2,SMD | NXP | BZT52H-C16 |  | PWA BOM | In Old BOM |
| 23 | PHAQ1,PHAQ2,PHAQ3 | 3 | 51031VY00-031-G | MOS N,PSMN4R8-100BSE,100V,120A,4.8m@10V,G,SOT404-3,SMD | NXP SEMICONDUCTORS | PSMN4R8-100BSE |  | PWA BOM | In New BOM |
|  |  |  | SUM70040E-GE3 | MOS N,SUM70040E-GE3 | VISHAY ENTER TECHNO LOGY.INC | SUM70040E-GE3 | G | PWA BOM | In New BOM |
|  |  |  | FDB047N10 | MOS N,FDB047N10 | FAIRCHILD SEMICONDUCTOR CORP | FDB047N10 | G | PWA BOM | In New BOM |
|  | PHAQ1,PHAQ2,PHAQ3 | 3 | 51031VY00-031-G | MOS N,PSMN4R8-100BSE,100V,120A,4.8m@10V,G,SOT404-3,SMD | NXP SEMICONDUCTORS | PSMN4R8-100BSE |  | PWA BOM | In Old BOM |
|  |  |  | SUM70040E-GE3 | MOS N,SUM70040E-GE3 | Vishay | SUM70040E-GE3 | G | PWA BOM | In Old BOM |
|  |  |  | FDB047N10 | MOS N,FDB047N10 | Fairchild | FDB047N10 | G | PWA BOM | In Old BOM |
| 24 | PHAQ4 | 1 | 51020A000-031-G | TRANS P,PBHV9115T,150V,1A,G,SOT23-3,SMD | NXP SEMICONDUCTORS | PBHV9115T |  | PWA BOM | In New BOM |
|  |  |  | 51020AF00-280-G | Trans PNP,MMBT5401,-150V,-500mA,SOT-23,3P,G | FAIRCHILD SEMICONDUCTOR CORP | MMBT5401 | G | PWA BOM | In New BOM |
|  |  |  | MMBT5401 | TRANS,150V,1A,G,SOT23-3,SMD | DIODES INCORPORATION | MMBT5401 |  | PWA BOM | In New BOM |
|  | PHAQ4 | 1 | 51020A000-031-G | TRANS P,PBHV9115T,150V,1A,G,SOT23-3,SMD | NXP SEMICONDUCTORS | PBHV9115T |  | PWA BOM | In Old BOM |
|  |  |  | 51020AF00-280-G | Trans PNP,MMBT5401,-150V,-500mA,SOT-23,3P,G | Fairchild | MMBT5401 | G | PWA BOM | In Old BOM |
| 25 | PHAQ5,PHAQ9 | 2 | 51032D100-237-G | MOS N,DMN10H220L-7,100V,1.6A,220m@10V,G,SOT-23-3,SMD | DIODES INCORPORATION | DMN10H220L-7 |  | PWA BOM | In New BOM |
|  |  |  | FQT7N10LTF | MOS N,FQT7N10LTF | FAIRCHILD SEMICONDUCTOR CORP | FQT7N10LTF | G | PWA BOM | In New BOM |
|  | PHAQ5,PHAQ9 | 2 | 51032D100-237-G | MOS N,DMN10H220L-7,100V,1.6A,220m@10V,G,SOT-23-3,SMD | DIODES INCORPORATION | DMN10H220L-7 |  | PWA BOM | In Old BOM |
|  |  |  | FQT7N10L | MOS N,FQT7N10L | Fairchild | FQT7N10L | G | PWA BOM | In Old BOM |
| 26 | PHAR2 | 1 | 61100DA00-017-G | RES,33KOhm,+/-0.1%,1/16W,G,SMD0402 | KOA SPEER ELECTRONICS, INC. | RN731ETTP3302B25 |  | PWA BOM | In New BOM |
|  |  |  | 61100DA00-012-G | RES,33KOhm,+/-0.1%,1/16W,G,SMD0402 | WALSIN TECHNOLOGY CORPORATION | WF04U3302BTL | G | PWA BOM | In New BOM |
|  |  |  | 61100DA00-011-G | RES,33KOhm,+/-0.1%,1/16W,G,SMD0402 | YAGEO CORPORATION COMPONENT | RT0402BRD0733KL | G | PWA BOM | In New BOM |
|  | PHAR2 | 1 | 61100DA00-017-G | RES,33KOhm,+/-0.1%,1/16W,G,SMD0402 | KOA SPEER ELECTRONICS, INC. | RN731ETTP3302B25 |  | PWA BOM | In Old BOM |
|  |  |  | 61100DA00-012-G | RES,33KOhm,+/-0.1%,1/16W,G,SMD0402 | WALSIN | WF04U3302BTL | G | PWA BOM | In Old BOM |
|  |  |  | 61100DA00-011-G | RES,33KOhm,+/-0.1%,1/16W,G,SMD0402 | YAGEO | RT0402BRD0733KL | G | PWA BOM | In Old BOM |
| 27 | PHAR4 | 1 | 610130Y00-017-G | RES,1 Ohm,+/-1%,1/3W,G,SMD1206 | KOA SPEER ELECTRONICS, INC. | SR732BTTD1R00F |  | PWA BOM | In New BOM |
|  |  |  | 610122P00-012-G | RES,1 Ohm,+/-1%,1/2W,G,SMD1206 | WALSIN TECHNOLOGY CORPORATION | WF12P1R00FTL | G | PWA BOM | In New BOM |
|  |  |  | 610122P00-011-G | RES,1 Ohm,+/-1%,1/2W,G,SMD1206 | YAGEO CORPORATION COMPONENT | RC1206FR-7W1RL | G | PWA BOM | In New BOM |
|  |  |  | 610122P00-044-G | RES,1 Ohm,+/-1%,1/2W,G,SMD1206 | TA-I TECHNOLOGY CO., LTD. | RMH12FT1R00 | G | PWA BOM | In New BOM |
|  | PHAR4 | 1 | 610130Y00-017-G | RES,1 Ohm,+/-1%,1/3W,G,SMD1206 | KOA SPEER ELECTRONICS, INC. | SR732BTTD1R00F |  | PWA BOM | In Old BOM |
|  |  |  | 610122P00-012-G | RES,1 Ohm,+/-1%,1/2W,G,SMD1206 | WALSIN | WF12P1R00FTL | G | PWA BOM | In Old BOM |
|  |  |  | 610122P00-011-G | RES,1 Ohm,+/-1%,1/2W,G,SMD1206 | YAGEO | RC1206FR-7W1RL | G | PWA BOM | In Old BOM |
|  |  |  | 610122P00-044-G | RES,1 Ohm,+/-1%,1/2W,G,SMD1206 | TA-I | RMH12FT1R00 | G | PWA BOM | In Old BOM |
| 28 | PHAR5,PHAR7 | 2 | 61100QM00-017-G | RES,100KOhm,+/-0.1%,1/10W,G,SMD0603 | KOA SPEER ELECTRONICS, INC. | RN73H1JTTD1003B25 |  | PWA BOM | In New BOM |
|  |  |  | 61100QM00-012-G | RES,100KOhm,+/-0.1%,1/10W,G,SMD0603 | WALSIN TECHNOLOGY CORPORATION | WF06Q1003BTL | G | PWA BOM | In New BOM |
|  |  |  | 61100QM00-011-G | RES,100KOhm,+/-0.1%,1/10W,G,SMD0603 | YAGEO CORPORATION COMPONENT | RT0603BRD07100KL | G | PWA BOM | In New BOM |
|  | PHAR5,PHAR7 | 2 | 61100QM00-017-G | RES,100KOhm,+/-0.1%,1/10W,G,SMD0603 | KOA SPEER ELECTRONICS, INC. | RN73H1JTTD1003B25 |  | PWA BOM | In Old BOM |
|  |  |  | 61100QM00-012-G | RES,100KOhm,+/-0.1%,1/10W,G,SMD0603 | WALSIN | WF06Q1003BTL | G | PWA BOM | In Old BOM |
|  |  |  | 61100QM00-011-G | RES,100KOhm,+/-0.1%,1/10W,G,SMD0603 | YAGEO | RT0603BRD07100KL | G | PWA BOM | In Old BOM |
| 29 | PHAR6 | 1 | 610100200-017-G | RES,7.5KOhm,+/-1%,1/10W,G,SMD0603 | KOA SPEER ELECTRONICS, INC. | RK73H1JTTD7501F | N | PWA BOM | In New BOM |
|  |  |  | 610100200-012-G | RES,7.5KOhm,+/-1%,1/10W,G,SMD0603 | WALSIN TECHNOLOGY CORPORATION | WR06X7501FTL | G | PWA BOM | In New BOM |
|  |  |  | 610100200-011-G | RES,7.5KOhm,+/-1%,1/10W,G,SMD0603 | YAGEO CORPORATION COMPONENT | RC0603FR-077K5L | G | PWA BOM | In New BOM |
|  |  |  | 610100200-044-G | RES,7.5KOhm,+/-1%,1/10W,G,SMD0603 | TA-I TECHNOLOGY CO., LTD. | RM06FTN7501 | G | PWA BOM | In New BOM |
|  | PHAR6 | 1 | 610100200-017-G | RES,7.5KOhm,+/-1%,1/10W,G,SMD0603 | KOA SPEER ELECTRONICS, INC. | RK73H1JTTD7501F | N | PWA BOM | In Old BOM |
|  |  |  | 610100200-012-G | RES,7.5KOhm,+/-1%,1/10W,G,SMD0603 | WALSIN | WR06X7501FTL | G | PWA BOM | In Old BOM |
|  |  |  | 610100200-011-G | RES,7.5KOhm,+/-1%,1/10W,G,SMD0603 | YAGEO | RC0603FR-077K5L | G | PWA BOM | In Old BOM |
|  |  |  | 610100200-044-G | RES,7.5KOhm,+/-1%,1/10W,G,SMD0603 | TA-I | RM06FTN7501 | G | PWA BOM | In Old BOM |
| 30 | PHAR8,PHAR14,PHAR15 | 3 | 610103Y00-017-G | RES,10 Ohm,+/-1%,1/10W,G,SMD0603 | KOA SPEER ELECTRONICS, INC. | RK73H1JTTD10R0F | N | PWA BOM | In New BOM |
|  |  |  | 610103Y00-011-G | RES,10 Ohm,+/-1%,1/10W,G,SMD0603 | YAGEO CORPORATION COMPONENT | RC0603FR-0710RL | G | PWA BOM | In New BOM |
|  |  |  | 610103Y00-044-G | RES,10 Ohm,+/-1%,1/10W,G,SMD0603 | TA-I TECHNOLOGY CO., LTD. | RM06FTN10R0 | G | PWA BOM | In New BOM |
|  |  |  | 610103Y00-012-G | RES,10 Ohm,+/-1%,1/10W,G,SMD0603 | WALSIN TECHNOLOGY CORPORATION | WR06X10R0FTL | G | PWA BOM | In New BOM |
|  |  |  | 610103Y00-024-G | RES,10 Ohm,+/-1%,1/10W,G,SMD0603 | PANASONIC INDUSTRIAL CO.,LTD. | ERJ3EKF10R0V | G | PWA BOM | In New BOM |
|  | PHAR8,PHAR14,PHAR15 | 3 | 610103Y00-017-G | RES,10 Ohm,+/-1%,1/10W,G,SMD0603 | KOA SPEER ELECTRONICS, INC. | RK73H1JTTD10R0F | N | PWA BOM | In Old BOM |
|  |  |  | 610103Y00-011-G | RES,10 Ohm,+/-1%,1/10W,G,SMD0603 | YAGEO | RC0603FR-0710RL | G | PWA BOM | In Old BOM |
|  |  |  | 610103Y00-044-G | RES,10 Ohm,+/-1%,1/10W,G,SMD0603 | TA-I | RM06FTN10R0 | G | PWA BOM | In Old BOM |
|  |  |  | 610103Y00-012-G | RES,10 Ohm,+/-1%,1/10W,G,SMD0603 | WALSIN | WR06X10R0FTL | G | PWA BOM | In Old BOM |
|  |  |  | 610103Y00-024-G | RES,10 Ohm,+/-1%,1/10W,G,SMD0603 | PANASONIC | ERJ3EKF10R0V | G | PWA BOM | In Old BOM |
| 31 | PHAR9 | 1 | 61010L300-017-G | RES,1KOhm,+/-1%,1/16W,G,SMD0402 | KOA SPEER ELECTRONICS, INC. | RK73H1ETTP1001F | N | PWA BOM | In New BOM |
|  |  |  | 61010L300-012-G | RES,1KOhm,+/-1%,1/16W,G,SMD0402 | WALSIN TECHNOLOGY CORPORATION | WR04X1001FTL | G | PWA BOM | In New BOM |
|  |  |  | 61010L300-011-G | RES,1KOhm,+/-1%,1/16W,G,SMD0402 | YAGEO CORPORATION COMPONENT | RC0402FR-071KL | G | PWA BOM | In New BOM |
|  |  |  | 61010L300-044-G | RES,1KOhm,+/-1%,1/16W,G,SMD0402 | TA-I TECHNOLOGY CO., LTD. | RM04FTN1001 | G | PWA BOM | In New BOM |
|  |  |  | 61010L300-024-G | RES,1KOhm,+/-1%,1/16W,G,SMD0402 | PANASONIC INDUSTRIAL CO.,LTD. | ERJ2RKF1001X | G | PWA BOM | In New BOM |
|  |  |  | 61010L300-029-G | RES,1KOhm,+/-1%,1/16W,G,SMD0402 | VISHAY ENTER TECHNO LOGY.INC | CRCW04021K00FKED | G | PWA BOM | In New BOM |
|  | PHAR9 | 1 | 61010L300-017-G | RES,1KOhm,+/-1%,1/16W,G,SMD0402 | KOA SPEER ELECTRONICS, INC. | RK73H1ETTP1001F | N | PWA BOM | In Old BOM |
|  |  |  | 61010L300-012-G | RES,1KOhm,+/-1%,1/16W,G,SMD0402 | WALSIN | WR04X1001FTL | G | PWA BOM | In Old BOM |
|  |  |  | 61010L300-011-G | RES,1KOhm,+/-1%,1/16W,G,SMD0402 | YAGEO | RC0402FR-071KL | G | PWA BOM | In Old BOM |
|  |  |  | 61010L300-044-G | RES,1KOhm,+/-1%,1/16W,G,SMD0402 | TA-I | RM04FTN1001 | G | PWA BOM | In Old BOM |
|  |  |  | 61010L300-024-G | RES,1KOhm,+/-1%,1/16W,G,SMD0402 | PANASONIC | ERJ2RKF1001X | G | PWA BOM | In Old BOM |
|  |  |  | 61010L300-029-G | RES,1KOhm,+/-1%,1/16W,G,SMD0402 | VISHAY | CRCW04021K00FKED | G | PWA BOM | In Old BOM |
| 32 | PHAR13 | 1 | 61013GW00-017-G | RES,150KOhm,+/-1%,1/8W,G,SMD0805 | KOA SPEER ELECTRONICS, INC. | RK73H2ATTD1503F | N | PWA BOM | In New BOM |
|  |  |  | 61013GW00-012-G | RES,150KOhm,+/-1%,1/8W,G,SMD0805 | WALSIN TECHNOLOGY CORPORATION | WR08X1503FTL | G | PWA BOM | In New BOM |
|  |  |  | 61013GW00-011-G | RES,150KOhm,+/-1%,1/8W,G,SMD0805 | YAGEO CORPORATION COMPONENT | RC0805FR-07150KL | G | PWA BOM | In New BOM |
|  |  |  | 61013GW00-044-G | RES,150KOhm,+/-1%,1/8W,G,SMD0805 | TA-I TECHNOLOGY CO., LTD. | RM10FTN1503 | G | PWA BOM | In New BOM |
|  | PHAR13 | 1 | 61013GW00-017-G | RES,150KOhm,+/-1%,1/8W,G,SMD0805 | KOA SPEER ELECTRONICS, INC. | RK73H2ATTD1503F | N | PWA BOM | In Old BOM |
|  |  |  | 61013GW00-012-G | RES,150KOhm,+/-1%,1/8W,G,SMD0805 | WALSIN | WR08X1503FTL | G | PWA BOM | In Old BOM |
|  |  |  | 61013GW00-011-G | RES,150KOhm,+/-1%,1/8W,G,SMD0805 | YAGEO | RC0805FR-07150KL | G | PWA BOM | In Old BOM |
|  |  |  | 61013GW00-044-G | RES,150KOhm,+/-1%,1/8W,G,SMD0805 | TA-I | RM10FTN1503 | G | PWA BOM | In Old BOM |
| 33 | PHAR20 | 1 | 610114F00-017-G | RES,3.16KOhm,+/-1%,1/16W,G,SMD0402 | KOA SPEER ELECTRONICS, INC. | RK73H1ETTP3161F | N | PWA BOM | In New BOM |
|  |  |  | 610114F00-012-G | RES,3.16KOhm,+/-1%,1/16W,G,SMD0402 | WALSIN TECHNOLOGY CORPORATION | WR04X3161FTL | G | PWA BOM | In New BOM |
|  |  |  | 610114F00-011-G | RES,3.16KOhm,+/-1%,1/16W,G,SMD0402 | YAGEO CORPORATION COMPONENT | RC0402FR-073K16L | G | PWA BOM | In New BOM |
|  |  |  | 610114F00-044-G | RES,3.16KOhm,+/-1%,1/16W,G,SMD0402 | TA-I TECHNOLOGY CO., LTD. | RM04FTN3161 | G | PWA BOM | In New BOM |
|  | PHAR20 | 1 | 610114F00-017-G | RES,3.16KOhm,+/-1%,1/16W,G,SMD0402 | KOA SPEER ELECTRONICS, INC. | RK73H1ETTP3161F | N | PWA BOM | In Old BOM |
|  |  |  | 610114F00-012-G | RES,3.16KOhm,+/-1%,1/16W,G,SMD0402 | WALSIN | WR04X3161FTL | G | PWA BOM | In Old BOM |
|  |  |  | 610114F00-011-G | RES,3.16KOhm,+/-1%,1/16W,G,SMD0402 | YAGEO | RC0402FR-073K16L | G | PWA BOM | In Old BOM |
|  |  |  | 610114F00-044-G | RES,3.16KOhm,+/-1%,1/16W,G,SMD0402 | TA-I | RM04FTN3161 | G | PWA BOM | In Old BOM |
| 34 | PHAR22 | 1 | 61011NM00-017-G | RES,6.81KOhm,+/-1%,1/16W,G,SMD0402 | KOA SPEER ELECTRONICS, INC. | RK73H1ETTP6811F | N | PWA BOM | In New BOM |
|  |  |  | 61011NM00-012-G | RES,6.81KOhm,+/-1%,1/16W,G,SMD0402 | WALSIN TECHNOLOGY CORPORATION | WR04X6811FTL | G | PWA BOM | In New BOM |
|  |  |  | 61011NM00-011-G | RES,6.81KOhm,+/-1%,1/16W,G,SMD0402 | YAGEO CORPORATION COMPONENT | RC0402FR-076K81L | G | PWA BOM | In New BOM |
|  |  |  | 61011NM00-044-G | RES,6.81KOhm,+/-1%,1/16W,G,SMD0402 | TA-I TECHNOLOGY CO., LTD. | RM04FTN6811 | G | PWA BOM | In New BOM |
|  | PHAR22 | 1 | 61011NM00-017-G | RES,6.81KOhm,+/-1%,1/16W,G,SMD0402 | KOA SPEER ELECTRONICS, INC. | RK73H1ETTP6811F | N | PWA BOM | In Old BOM |
|  |  |  | 61011NM00-012-G | RES,6.81KOhm,+/-1%,1/16W,G,SMD0402 | WALSIN | WR04X6811FTL | G | PWA BOM | In Old BOM |
|  |  |  | 61011NM00-011-G | RES,6.81KOhm,+/-1%,1/16W,G,SMD0402 | YAGEO | RC0402FR-076K81L | G | PWA BOM | In Old BOM |
|  |  |  | 61011NM00-044-G | RES,6.81KOhm,+/-1%,1/16W,G,SMD0402 | TA-I | RM04FTN6811 | G | PWA BOM | In Old BOM |
| 35 | R2,R3,R4,R12,R13,R14,R18,R19,R20,R21,R22,R25,R26,R27,R28,PHAR28,R29,PHAR29,PHAR30,R34,R35,R36,R39,R40,R41,R42,R43,R46,R47,R48,R49,R50,R54,R55,R114,R115,R126,R127,R141,R154,R156,R169,R170,R178,R179,R190,R191,R501,R1822,R1823 | 50 | 61010LA00-017-G | RES,4.7KOhm,+/-1%,1/16W,G,SMD0402 | KOA SPEER ELECTRONICS, INC. | RK73H1ETTP4701F | N | PWA BOM | In New BOM |
|  |  |  | 61010LA00-012-G | RES,4.7KOhm,+/-1%,1/16W,G,SMD0402 | WALSIN TECHNOLOGY CORPORATION | WR04X4701FTL | G | PWA BOM | In New BOM |
|  |  |  | 61010LA00-011-G | RES,4.7KOhm,+/-1%,1/16W,G,SMD0402 | YAGEO CORPORATION COMPONENT | RC0402FR-074K7L | G | PWA BOM | In New BOM |
|  |  |  | 61010LA00-044-G | RES,4.7KOhm,+/-1%,1/16W,G,SMD0402 | TA-I TECHNOLOGY CO., LTD. | RM04FTN4701 | G | PWA BOM | In New BOM |
|  | R2,R3,R4,R12,R13,R14,R18,R19,R20,R21,R22,R25,R26,R27,R28,PHAR28,R29,PHAR29,PHAR30,R34,R35,R36,R39,R40,R41,R42,R43,R46,R47,R48,R49,R50,R54,R55,R114,R115,R126,R127,R141,R154,R156,R169,R170,R178,R179,R190,R191,R501,R1822,R1823 | 50 | 61010LA00-017-G | RES,4.7KOhm,+/-1%,1/16W,G,SMD0402 | KOA SPEER ELECTRONICS, INC. | RK73H1ETTP4701F | N | PWA BOM | In Old BOM |
|  |  |  | 61010LA00-012-G | RES,4.7KOhm,+/-1%,1/16W,G,SMD0402 | WALSIN | WR04X4701FTL | G | PWA BOM | In Old BOM |
|  |  |  | 61010LA00-011-G | RES,4.7KOhm,+/-1%,1/16W,G,SMD0402 | YAGEO | RC0402FR-074K7L | G | PWA BOM | In Old BOM |
|  |  |  | 61010LA00-044-G | RES,4.7KOhm,+/-1%,1/16W,G,SMD0402 | TA-I | RM04FTN4701 | G | PWA BOM | In Old BOM |
| 36 | PHAR35 | 1 | 61011PE00-017-G | RES,8.87KOhm,+/-1%,1/16W,G,SMD0402 | KOA SPEER ELECTRONICS, INC. | RK73H1ETTP8871F | N | PWA BOM | In New BOM |
|  |  |  | 61011PE00-012-G | RES,8.87KOhm,+/-1%,1/16W,G,SMD0402 | WALSIN TECHNOLOGY CORPORATION | WR04X8871FTL | G | PWA BOM | In New BOM |
|  |  |  | 61011PE00-011-G | RES,8.87KOhm,+/-1%,1/16W,G,SMD0402 | YAGEO CORPORATION COMPONENT | RC0402FR-078K87L | G | PWA BOM | In New BOM |
|  |  |  | 61011PE00-044-G | RES,8.87KOhm,+/-1%,1/16W,G,SMD0402 | TA-I TECHNOLOGY CO., LTD. | RM04FTN8871 | G | PWA BOM | In New BOM |
|  | PHAR35 | 1 | 61011PE00-017-G | RES,8.87KOhm,+/-1%,1/16W,G,SMD0402 | KOA SPEER ELECTRONICS, INC. | RK73H1ETTP8871F | N | PWA BOM | In Old BOM |
|  |  |  | 61011PE00-012-G | RES,8.87KOhm,+/-1%,1/16W,G,SMD0402 | WALSIN | WR04X8871FTL | G | PWA BOM | In Old BOM |
|  |  |  | 61011PE00-011-G | RES,8.87KOhm,+/-1%,1/16W,G,SMD0402 | YAGEO | RC0402FR-078K87L | G | PWA BOM | In Old BOM |
|  |  |  | 61011PE00-044-G | RES,8.87KOhm,+/-1%,1/16W,G,SMD0402 | TA-I | RM04FTN8871 | G | PWA BOM | In Old BOM |
| 37 | PSRR6,R23,PHAR39,R119,R121,R131,R133,R138,R159,R162,R172,R174,R183,R185,R195,R197,R234 | 17 | 61010G500-017-G | RES,10KOhm,+/-1%,1/16W,G,SMD0402 | KOA SPEER ELECTRONICS, INC. | RK73H1ETTP1002F | N | PWA BOM | In New BOM |
|  |  |  | 61010G500-012-G | RES,10KOhm,+/-1%,1/16W,G,SMD0402 | WALSIN TECHNOLOGY CORPORATION | WR04X1002FTL | G | PWA BOM | In New BOM |
|  |  |  | 61010G500-011-G | RES,10KOhm,+/-1%,1/16W,G,SMD0402 | YAGEO CORPORATION COMPONENT | RC0402FR-0710KL | G | PWA BOM | In New BOM |
|  |  |  | 61010G500-044-G | RES,10KOhm,+/-1%,1/16W,G,SMD0402 | TA-I TECHNOLOGY CO., LTD. | RM04FTN1002 | G | PWA BOM | In New BOM |
|  |  |  | 61010G500-029-G | RES,10KOhm,+/-1%,1/16W,G,SMD0402 | VISHAY ENTER TECHNO LOGY.INC | CRCW040210K0FKED | G | PWA BOM | In New BOM |
|  |  |  | 61010G500-024-G | RES,10KOhm,+/-1%,1/16W,G,SMD0402 | PANASONIC INDUSTRIAL CO.,LTD. | ERJ2RKF1002X | G | PWA BOM | In New BOM |
|  | PEUR1,PSRR6,R23,PHAR39,R119,R121,R131,R133,R138,R159,R162,R172,R174,R183,R185,R195,R197,R234 | 18 | 61010G500-017-G | RES,10KOhm,+/-1%,1/16W,G,SMD0402 | KOA SPEER ELECTRONICS, INC. | RK73H1ETTP1002F | N | PWA BOM | In Old BOM |
|  |  |  | 61010G500-012-G | RES,10KOhm,+/-1%,1/16W,G,SMD0402 | WALSIN | WR04X1002FTL | G | PWA BOM | In Old BOM |
|  |  |  | 61010G500-011-G | RES,10KOhm,+/-1%,1/16W,G,SMD0402 | YAGEO | RC0402FR-0710KL | G | PWA BOM | In Old BOM |
|  |  |  | 61010G500-044-G | RES,10KOhm,+/-1%,1/16W,G,SMD0402 | TA-I | RM04FTN1002 | G | PWA BOM | In Old BOM |
|  |  |  | 61010G500-029-G | RES,10KOhm,+/-1%,1/16W,G,SMD0402 | VISHAY | CRCW040210K0FKED | G | PWA BOM | In Old BOM |
|  |  |  | 61010G500-024-G | RES,10KOhm,+/-1%,1/16W,G,SMD0402 | PANASONIC | ERJ2RKF1002X | G | PWA BOM | In Old BOM |
| 38 | PHAR44 | 1 | 610107H00-017-G | RES,4.02KOhm,+/-1%,1/10W,G,SMD0603 | KOA SPEER ELECTRONICS, INC. | RK73H1JTTD4021F | N | PWA BOM | In New BOM |
|  |  |  | 610107H00-012-G | RES,4.02KOhm,+/-1%,1/10W,G,SMD0603 | WALSIN TECHNOLOGY CORPORATION | WR06X4021FTL | G | PWA BOM | In New BOM |
|  |  |  | 610107H00-011-G | RES,4.02KOhm,+/-1%,1/10W,G,SMD0603 | YAGEO CORPORATION COMPONENT | RC0603FR-074K02L | G | PWA BOM | In New BOM |
|  |  |  | 610107H00-044-G | RES,4.02KOhm,+/-1%,1/10W,G,SMD0603 | TA-I TECHNOLOGY CO., LTD. | RM06FTN4021 | G | PWA BOM | In New BOM |
|  | PHAR44 | 1 | 610107H00-017-G | RES,4.02KOhm,+/-1%,1/10W,G,SMD0603 | KOA SPEER ELECTRONICS, INC. | RK73H1JTTD4021F | N | PWA BOM | In Old BOM |
|  |  |  | 610107H00-012-G | RES,4.02KOhm,+/-1%,1/10W,G,SMD0603 | WALSIN | WR06X4021FTL | G | PWA BOM | In Old BOM |
|  |  |  | 610107H00-011-G | RES,4.02KOhm,+/-1%,1/10W,G,SMD0603 | YAGEO | RC0603FR-074K02L | G | PWA BOM | In Old BOM |
|  |  |  | 610107H00-044-G | RES,4.02KOhm,+/-1%,1/10W,G,SMD0603 | TA-I | RM06FTN4021 | G | PWA BOM | In Old BOM |
| 39 | PSRC3 | 1 | 62012GG00-015-G | CAP,10uF,+/-10%,X7S,25V,G,SMD0805 | MURATA ELEC. NORTH AMERICA | GRM21BC71E106K |  | PWA BOM | In New BOM |
|  |  |  | 62012GG00-012-G | CAP,10uF,+/-10%,X7S,25V,G,SMD0805 | WALSIN TECHNOLOGY CORPORATION | 0805A106K250CT | G | PWA BOM | In New BOM |
|  | PSRC3 | 1 | 62012GG00-015-G | CAP,10uF,+/-10%,X7S,25V,G,SMD0805 | MURATA ELEC. NORTH AMERICA | GRM21BC71E106K |  | PWA BOM | In Old BOM |
|  |  |  | 62012GG00-012-G | CAP,10uF,+/-10%,X7S,25V,G,SMD0805 | WALSIN | 0805A106K250CT | G | PWA BOM | In Old BOM |
| 40 | PSRC5 | 1 | 62012P100-015-G | CAP,2.2uF,+/-20%,X7S,10V,G,SMD0402 | MURATA ELEC. NORTH AMERICA | GRM155C71A225M |  | PWA BOM | In New BOM |
|  |  |  | 62012P100-012-G | CAP,2.2uF,+/-20%,X7S,10V,G,SMD0402 | WALSIN TECHNOLOGY CORPORATION | 0402A225M100CT | G | PWA BOM | In New BOM |
|  | PSRC5 | 1 | 62012P100-015-G | CAP,2.2uF,+/-20%,X7S,10V,G,SMD0402 | MURATA ELEC. NORTH AMERICA | GRM155C71A225M |  | PWA BOM | In Old BOM |
|  |  |  | 62012P100-012-G | CAP,2.2uF,+/-20%,X7S,10V,G,SMD0402 | WALSIN | 0402A225M100CT | G | PWA BOM | In Old BOM |
| 41 | PSRC7,PSRC8,PSRC11,PSRC12,PSRC15 | 5 | 62012PT00-015-G | CAP,22uF,+/-20%,X6S,16V,G,SMD0805 | MURATA ELEC. NORTH AMERICA | GRM21BC81C226M |  | PWA BOM | In New BOM |
|  |  |  | 62012PT00-023-G | CAP,22uF,+/-20%,X6S,16V,G,SMD0805 | TAIYO ELECTRIC IND.CO.LTD | EDK212BC6226MG-T | G | PWA BOM | In New BOM |
|  | PSRC7,PSRC8,PSRC11,PSRC12,PSRC15 | 5 | 62012PT00-015-G | CAP,22uF,+/-20%,X6S,16V,G,SMD0805 | MURATA ELEC. NORTH AMERICA | GRM21BC81C226M |  | PWA BOM | In Old BOM |
|  |  |  | 62012PT00-023-G | CAP,22uF,+/-20%,X6S,16V,G,SMD0805 | TAIYO | EDK212BC6226MG-T | G | PWA BOM | In Old BOM |
| 42 | PSRC14 | 1 | 620105U00-015-G | CAP,220pF,+/-10%,X7R,50V,G,SMD0402 | MURATA ELEC. NORTH AMERICA | GRM155R71H221K | N | PWA BOM | In New BOM |
|  |  |  | 620105U00-012-G | CAP,220pF,+/-10%,X7R,50V,G,SMD0402 | WALSIN TECHNOLOGY CORPORATION | 0402B221K500CT | G | PWA BOM | In New BOM |
|  |  |  | 620105U00-026-G | CAP,220pF,+/-10%,X7R,50V,G,SMD0402 | SAMSUNG SEMICONDUCTOR | CL05B221KB5NNNC | G | PWA BOM | In New BOM |
|  | PSRC14 | 1 | 620105U00-015-G | CAP,220pF,+/-10%,X7R,50V,G,SMD0402 | MURATA ELEC. NORTH AMERICA | GRM155R71H221K | N | PWA BOM | In Old BOM |
|  |  |  | 620105U00-012-G | CAP,220pF,+/-10%,X7R,50V,G,SMD0402 | WALSIN | 0402B221K500CT | G | PWA BOM | In Old BOM |
|  |  |  | 620105U00-026-G | CAP,220pF,+/-10%,X7R,50V,G,SMD0402 | SAMSUNG | CL05B221KB5NNNC | G | PWA BOM | In Old BOM |
| 43 | PSRC16 | 1 | 62012H100-015-G | CAP,10uF,+/-20%,X6S,10V,G,SMD0603 | MURATA ELEC. NORTH AMERICA | GRM188C81A106M |  | PWA BOM | In New BOM |
|  |  |  | 62012H100-023-G | CAP,10uF,+/-20%,X6S,10V,G,SMD0603 | TAIYO ELECTRIC IND.CO.LTD | LMK107BC6106MA-T | G | PWA BOM | In New BOM |
|  |  |  | 62012H100-026-G | CAP,10uF,+/-20%,X6S,10V,G,SMD0603 | SAMSUNG SEMICONDUCTOR | CL10X106MP8NRNC | G | PWA BOM | In New BOM |
|  | PSRC16 | 1 | 62012H100-015-G | CAP,10uF,+/-20%,X6S,10V,G,SMD0603 | MURATA ELEC. NORTH AMERICA | GRM188C81A106M |  | PWA BOM | In Old BOM |
|  |  |  | 62012H100-023-G | CAP,10uF,+/-20%,X6S,10V,G,SMD0603 | TAIYO | LMK107BC6106MA-T | G | PWA BOM | In Old BOM |
|  |  |  | 62012H100-026-G | CAP,10uF,+/-20%,X6S,10V,G,SMD0603 | SAMSUNG | CL10X106MP8NRNC | G | PWA BOM | In Old BOM |
| 44 | PSRL1 | 1 | 72010RE00-015-G | FB,26 Ohm@100MHz,+/-25%,6A,7mOhm,G,SMD0603 | MURATA ELEC. NORTH AMERICA | BLM18KG260TN1D | N | PWA BOM | In New BOM |
|  |  |  | 72010SJ00-059-G | FB,26 Ohm@100MHz,+/-25%,6A,10mOhm,G,SMD0603 | TAI-TECH ADVANCED ELECTRONICS CO., LTD. | HCB1608KF-260T60 | G | PWA BOM | In New BOM |
|  | PSRL1 | 1 | 72010RE00-015-G | FB,26 Ohm@100MHz,+/-25%,6A,7mOhm,G,SMD0603 | MURATA ELEC. NORTH AMERICA | BLM18KG260TN1D | N | PWA BOM | In Old BOM |
|  |  |  | 72010SJ00-059-G | FB,26 Ohm@100MHz,+/-25%,6A,10mOhm,G,SMD0603 | TAI-TECH | HCB1608KF-260T60 | G | PWA BOM | In Old BOM |
| 45 | PSRR1 | 1 | 61011R400-017-G | RES,34.8KOhm,+/-1%,1/16W,G,SMD0402 | KOA SPEER ELECTRONICS, INC. | RK73H1ETTP3482F | N | PWA BOM | In New BOM |
|  |  |  | 61011R400-012-G | RES,34.8KOhm,+/-1%,1/16W,G,SMD0402 | WALSIN TECHNOLOGY CORPORATION | WR04X3482FTL | G | PWA BOM | In New BOM |
|  |  |  | 61011R400-011-G | RES,34.8KOhm,+/-1%,1/16W,G,SMD0402 | YAGEO CORPORATION COMPONENT | RC0402FR-0734K8L | G | PWA BOM | In New BOM |
|  |  |  | 61011R400-044-G | RES,34.8KOhm,+/-1%,1/16W,G,SMD0402 | TA-I TECHNOLOGY CO., LTD. | RM04FTN3482 | G | PWA BOM | In New BOM |
|  | PSRR1 | 1 | 61011R400-017-G | RES,34.8KOhm,+/-1%,1/16W,G,SMD0402 | KOA SPEER ELECTRONICS, INC. | RK73H1ETTP3482F | N | PWA BOM | In Old BOM |
|  |  |  | 61011R400-012-G | RES,34.8KOhm,+/-1%,1/16W,G,SMD0402 | WALSIN | WR04X3482FTL | G | PWA BOM | In Old BOM |
|  |  |  | 61011R400-011-G | RES,34.8KOhm,+/-1%,1/16W,G,SMD0402 | YAGEO | RC0402FR-0734K8L | G | PWA BOM | In Old BOM |
|  |  |  | 61011R400-044-G | RES,34.8KOhm,+/-1%,1/16W,G,SMD0402 | TA-I | RM04FTN3482 | G | PWA BOM | In Old BOM |
| 46 | PSRR3 | 1 | 610114S00-017-G | RES,4.99KOhm,+/-1%,1/16W,G,SMD0402 | KOA SPEER ELECTRONICS, INC. | RK73H1ETTP4991F | N | PWA BOM | In New BOM |
|  |  |  | 610114S00-012-G | RES,4.99KOhm,+/-1%,1/16W,G,SMD0402 | WALSIN TECHNOLOGY CORPORATION | WR04X4991FTL | G | PWA BOM | In New BOM |
|  |  |  | 610114S00-011-G | RES,4.99KOhm,+/-1%,1/16W,G,SMD0402 | YAGEO CORPORATION COMPONENT | RC0402FR-074K99L | G | PWA BOM | In New BOM |
|  |  |  | 610114S00-044-G | RES,4.99KOhm,+/-1%,1/16W,G,SMD0402 | TA-I TECHNOLOGY CO., LTD. | RM04FTN4991 | G | PWA BOM | In New BOM |
|  |  |  | 610114S00-024-G | RES,4.99KOhm,+/-1%,1/16W,G,SMD0402 | PANASONIC INDUSTRIAL CO.,LTD. | ERJ2RKF4991X | G | PWA BOM | In New BOM |
|  | PSRR3 | 1 | 610114S00-017-G | RES,4.99KOhm,+/-1%,1/16W,G,SMD0402 | KOA SPEER ELECTRONICS, INC. | RK73H1ETTP4991F | N | PWA BOM | In Old BOM |
|  |  |  | 610114S00-012-G | RES,4.99KOhm,+/-1%,1/16W,G,SMD0402 | WALSIN | WR04X4991FTL | G | PWA BOM | In Old BOM |
|  |  |  | 610114S00-011-G | RES,4.99KOhm,+/-1%,1/16W,G,SMD0402 | YAGEO | RC0402FR-074K99L | G | PWA BOM | In Old BOM |
|  |  |  | 610114S00-044-G | RES,4.99KOhm,+/-1%,1/16W,G,SMD0402 | TA-I | RM04FTN4991 | G | PWA BOM | In Old BOM |
|  |  |  | 610114S00-024-G | RES,4.99KOhm,+/-1%,1/16W,G,SMD0402 | PANASONIC | ERJ2RKF4991X | G | PWA BOM | In Old BOM |
| 47 | PSRR5 | 1 | 61011HA00-017-G | RES,1 Ohm,+/-1%,1/16W,G,SMD0402 | KOA SPEER ELECTRONICS, INC. | RK73H1ETTP1R00F | N | PWA BOM | In New BOM |
|  |  |  | 61011HA00-012-G | RES,1 Ohm,+/-1%,1/16W,G,SMD0402 | WALSIN TECHNOLOGY CORPORATION | WR04W1R00FTL | G | PWA BOM | In New BOM |
|  |  |  | 61011HA00-011-G | RES,1 Ohm,+/-1%,1/16W,G,SMD0402 | YAGEO CORPORATION COMPONENT | RC0402FR-071RL | G | PWA BOM | In New BOM |
|  |  |  | 61011HA00-044-G | RES,1 Ohm,+/-1%,1/16W,G,SMD0402 | TA-I TECHNOLOGY CO., LTD. | RM04FTN1R00 | G | PWA BOM | In New BOM |
|  |  |  | 61011HA00-029-G | RES,1 Ohm,+/-1%,1/16W,G,SMD0402 | VISHAY ENTER TECHNO LOGY.INC | CRCW04021R00FNED | G | PWA BOM | In New BOM |
|  | PSRR5 | 1 | 61011HA00-017-G | RES,1 Ohm,+/-1%,1/16W,G,SMD0402 | KOA SPEER ELECTRONICS, INC. | RK73H1ETTP1R00F | N | PWA BOM | In Old BOM |
|  |  |  | 61011HA00-012-G | RES,1 Ohm,+/-1%,1/16W,G,SMD0402 | WALSIN | WR04W1R00FTL | G | PWA BOM | In Old BOM |
|  |  |  | 61011HA00-011-G | RES,1 Ohm,+/-1%,1/16W,G,SMD0402 | YAGEO | RC0402FR-071RL | G | PWA BOM | In Old BOM |
|  |  |  | 61011HA00-044-G | RES,1 Ohm,+/-1%,1/16W,G,SMD0402 | TA-I | RM04FTN1R00 | G | PWA BOM | In Old BOM |
|  |  |  | 61011HA00-029-G | RES,1 Ohm,+/-1%,1/16W,G,SMD0402 | VISHAY | CRCW04021R00FNED | G | PWA BOM | In Old BOM |
| 48 | PSRR17 | 1 | 611004M00-017-G | RES,16.5KOhm,+/-0.1%,1/16W,G,SMD0402 | KOA SPEER ELECTRONICS, INC. | RN731ETTP1652B25 |  | PWA BOM | In New BOM |
|  |  |  | 611004M00-024-G | RES,16.5KOhm,+/-0.1%,1/16W,G,SMD0402 | PANASONIC INDUSTRIAL CO.,LTD. | ERA2AEB1652X | G | PWA BOM | In New BOM |
|  | PSRR17 | 1 | 611004M00-017-G | RES,16.5KOhm,+/-0.1%,1/16W,G,SMD0402 | KOA SPEER ELECTRONICS, INC. | RN731ETTP1652B25 |  | PWA BOM | In Old BOM |
|  |  |  | 611004M00-024-G | RES,16.5KOhm,+/-0.1%,1/16W,G,SMD0402 | PANASONIC | ERA2AEB1652X | G | PWA BOM | In Old BOM |
| 49 | QN4 | 1 | 510503B00-223-G | MOS N/N,NTZD3154NT1G,20V,0.54A,550m24.5V,G,SOT563-6,SMD | ON SEMICONDUCTOR CORP | NTZD3154NT1G | N | PWA BOM | In New BOM |
|  |  |  | Si1034CX-T1-GE3 | MOS N/N,Si1034CX-T1-GE3 | VISHAY ENTER TECHNO LOGY.INC | Si1034CX-T1-GE3 | G | PWA BOM | In New BOM |
|  |  |  | SSM6N36FE | MOS N/N,SSM6N36FE | TOSHIBA ELECTRONICS ASIA LTD | SSM6N36FE | G | PWA BOM | In New BOM |
|  | QN4 | 1 | 510503B00-223-G | MOS N/N,NTZD3154NT1G,20V,0.54A,550m24.5V,G,SOT563-6,SMD | ON SEMICONDUCTOR CORP | NTZD3154NT1G | N | PWA BOM | In Old BOM |
|  |  |  | 51050AK00-030-G | MOS N/N,EM6K6T2R,20V,0.3A,1ohm@4V,G,EMT-6,SMD | ROHM CORPORATION | EM6K6T2R | G | PWA BOM | In Old BOM |
|  |  |  | Si1034CX-T1-GE3 | MOS N/N,Si1034CX-T1-GE3 | Vishay | Si1034CX-T1-GE3 | G | PWA BOM | In Old BOM |
|  |  |  | SSM6N36FE | MOS N/N,SSM6N36FE | Toshiba | SSM6N36FE | G | PWA BOM | In Old BOM |
| 50 | R11,R32 | 2 | 61010H800-017-G | RES,5.11 Ohm,+/-1%,1/10W,G,SMD0603 | KOA SPEER ELECTRONICS, INC. | RK73H1JTTD5R11F | N | PWA BOM | In New BOM |
|  |  |  | 61010H800-012-G | RES,5.11 Ohm,+/-1%,1/10W,G,SMD0603 | WALSIN TECHNOLOGY CORPORATION | WR06W5R11FTL | G | PWA BOM | In New BOM |
|  |  |  | 61010H800-011-G | RES,5.11 Ohm,+/-1%,1/10W,G,SMD0603 | YAGEO CORPORATION COMPONENT | RC0603FR-075R11L | G | PWA BOM | In New BOM |
|  |  |  | 61010H800-044-G | RES,5.11 Ohm,+/-1%,1/10W,G,SMD0603 | TA-I TECHNOLOGY CO., LTD. | RM06FTN5R11 | G | PWA BOM | In New BOM |
|  | R11,R32 | 2 | 61010H800-017-G | RES,5.11 Ohm,+/-1%,1/10W,G,SMD0603 | KOA SPEER ELECTRONICS, INC. | RK73H1JTTD5R11F | N | PWA BOM | In Old BOM |
|  |  |  | 61010H800-012-G | RES,5.11 Ohm,+/-1%,1/10W,G,SMD0603 | WALSIN | WR06W5R11FTL | G | PWA BOM | In Old BOM |
|  |  |  | 61010H800-011-G | RES,5.11 Ohm,+/-1%,1/10W,G,SMD0603 | YAGEO | RC0603FR-075R11L | G | PWA BOM | In Old BOM |
|  |  |  | 61010H800-044-G | RES,5.11 Ohm,+/-1%,1/10W,G,SMD0603 | TA-I | RM06FTN5R11 | G | PWA BOM | In Old BOM |
| 51 | R15,R33,R1772,R1814 | 4 | 61011MQ00-017-G | RES,4.75KOhm,+/-1%,1/16W,G,SMD0402 | KOA SPEER ELECTRONICS, INC. | RK73H1ETTP4751F | N | PWA BOM | In New BOM |
|  |  |  | 61011MQ00-012-G | RES,4.75KOhm,+/-1%,1/16W,G,SMD0402 | WALSIN TECHNOLOGY CORPORATION | WR04X4751FTL | G | PWA BOM | In New BOM |
|  |  |  | 61011MQ00-011-G | RES,4.75KOhm,+/-1%,1/16W,G,SMD0402 | YAGEO CORPORATION COMPONENT | RC0402FR-074K75L | G | PWA BOM | In New BOM |
|  |  |  | 61011MQ00-044-G | RES,4.75KOhm,+/-1%,1/16W,G,SMD0402 | TA-I TECHNOLOGY CO., LTD. | RM04FTN4751 | G | PWA BOM | In New BOM |
|  | R15,R33,R1772,R1814 | 4 | 61011MQ00-017-G | RES,4.75KOhm,+/-1%,1/16W,G,SMD0402 | KOA SPEER ELECTRONICS, INC. | RK73H1ETTP4751F | N | PWA BOM | In Old BOM |
|  |  |  | 61011MQ00-012-G | RES,4.75KOhm,+/-1%,1/16W,G,SMD0402 | WALSIN | WR04X4751FTL | G | PWA BOM | In Old BOM |
|  |  |  | 61011MQ00-011-G | RES,4.75KOhm,+/-1%,1/16W,G,SMD0402 | YAGEO | RC0402FR-074K75L | G | PWA BOM | In Old BOM |
|  |  |  | 61011MQ00-044-G | RES,4.75KOhm,+/-1%,1/16W,G,SMD0402 | TA-I | RM04FTN4751 | G | PWA BOM | In Old BOM |
| 52 | R17,R37 | 2 | 610115J00-017-G | RES,33 Ohm,+/-1%,1/16W,G,SMD0402 | KOA SPEER ELECTRONICS, INC. | RK73H1ETTP33R0F | N | PWA BOM | In New BOM |
|  |  |  | 610115J00-012-G | RES,33 Ohm,+/-1%,1/16W,G,SMD0402 | WALSIN TECHNOLOGY CORPORATION | WR04X33R0FTL | G | PWA BOM | In New BOM |
|  |  |  | 610115J00-011-G | RES,33 Ohm,+/-1%,1/16W,G,SMD0402 | YAGEO CORPORATION COMPONENT | RC0402FR-0733RL | G | PWA BOM | In New BOM |
|  |  |  | 610115J00-044-G | RES,33 Ohm,+/-1%,1/16W,G,SMD0402 | TA-I TECHNOLOGY CO., LTD. | RM04FTN33R0 | G | PWA BOM | In New BOM |
|  |  |  | 610115J00-024-G | RES,33 Ohm,+/-1%,1/16W,G,SMD0402 | PANASONIC INDUSTRIAL CO.,LTD. | ERJ2RKF33R0X | G | PWA BOM | In New BOM |
|  | R17,R37 | 2 | 610115J00-017-G | RES,33 Ohm,+/-1%,1/16W,G,SMD0402 | KOA SPEER ELECTRONICS, INC. | RK73H1ETTP33R0F | N | PWA BOM | In Old BOM |
|  |  |  | 610115J00-012-G | RES,33 Ohm,+/-1%,1/16W,G,SMD0402 | WALSIN | WR04X33R0FTL | G | PWA BOM | In Old BOM |
|  |  |  | 610115J00-011-G | RES,33 Ohm,+/-1%,1/16W,G,SMD0402 | YAGEO | RC0402FR-0733RL | G | PWA BOM | In Old BOM |
|  |  |  | 610115J00-044-G | RES,33 Ohm,+/-1%,1/16W,G,SMD0402 | TA-I | RM04FTN33R0 | G | PWA BOM | In Old BOM |
|  |  |  | 610115J00-024-G | RES,33 Ohm,+/-1%,1/16W,G,SMD0402 | PANASONIC | ERJ2RKF33R0X | G | PWA BOM | In Old BOM |
| 53 | R45,R233,R236 | 3 | 61010L100-017-G | RES,100KOhm,+/-1%,1/16W,G,SMD0402 | KOA SPEER ELECTRONICS, INC. | RK73H1ETTP1003F | N | PWA BOM | In New BOM |
|  |  |  | 61010L100-012-G | RES,100KOhm,+/-1%,1/16W,G,SMD0402 | WALSIN TECHNOLOGY CORPORATION | WR04X1003FTL | G | PWA BOM | In New BOM |
|  |  |  | 61010L100-011-G | RES,100KOhm,+/-1%,1/16W,G,SMD0402 | YAGEO CORPORATION COMPONENT | RC0402FR-07100KL | G | PWA BOM | In New BOM |
|  |  |  | 61010L100-044-G | RES,100KOhm,+/-1%,1/16W,G,SMD0402 | TA-I TECHNOLOGY CO., LTD. | RM04FTN1003 | G | PWA BOM | In New BOM |
|  |  |  | 61010L106-029-G | RES,100KOhm,+/-1%,1/16W,G,SMD0402 | VISHAY ENTER TECHNO LOGY.INC | CRCW0402100KFKEDC | G | PWA BOM | In New BOM |
|  |  |  | 61010L100-024-G | RES,100KOhm,+/-1%,1/16W,G,SMD0402 | PANASONIC INDUSTRIAL CO.,LTD. | ERJ2RKF1003X | G | PWA BOM | In New BOM |
|  | R45,R233,R236 | 3 | 61010L100-017-G | RES,100KOhm,+/-1%,1/16W,G,SMD0402 | KOA SPEER ELECTRONICS, INC. | RK73H1ETTP1003F | N | PWA BOM | In Old BOM |
|  |  |  | 61010L100-012-G | RES,100KOhm,+/-1%,1/16W,G,SMD0402 | WALSIN | WR04X1003FTL | G | PWA BOM | In Old BOM |
|  |  |  | 61010L100-011-G | RES,100KOhm,+/-1%,1/16W,G,SMD0402 | YAGEO | RC0402FR-07100KL | G | PWA BOM | In Old BOM |
|  |  |  | 61010L100-044-G | RES,100KOhm,+/-1%,1/16W,G,SMD0402 | TA-I | RM04FTN1003 | G | PWA BOM | In Old BOM |
|  |  |  | 61010L106-029-G | RES,100KOhm,+/-1%,1/16W,G,SMD0402 | VISHAY | CRCW0402100KFKEDC | G | PWA BOM | In Old BOM |
|  |  |  | 61010L100-024-G | RES,100KOhm,+/-1%,1/16W,G,SMD0402 | PANASONIC | ERJ2RKF1003X | G | PWA BOM | In Old BOM |
| 54 | R59,R61,R73,R75,R87,R89,R116,R117,R118,R128,R129,R130,R155,R157,R158,R166,R167,R168,R180,R181,R182,R192,R193,R194 | 24 | 61011DR00-017-G | RES,2.2KOhm,+/-1%,1/16W,G,SMD0402 | KOA SPEER ELECTRONICS, INC. | RK73H1ETTP2201F | N | PWA BOM | In New BOM |
|  |  |  | 61011DR00-012-G | RES,2.2KOhm,+/-1%,1/16W,G,SMD0402 | WALSIN TECHNOLOGY CORPORATION | WR04X2201FTL | G | PWA BOM | In New BOM |
|  |  |  | 61011DR00-011-G | RES,2.2KOhm,+/-1%,1/16W,G,SMD0402 | YAGEO CORPORATION COMPONENT | RC0402FR-072K2L | G | PWA BOM | In New BOM |
|  |  |  | 61011DR00-044-G | RES,2.2KOhm,+/-1%,1/16W,G,SMD0402 | TA-I TECHNOLOGY CO., LTD. | RM04FTN2201 | G | PWA BOM | In New BOM |
|  |  |  | 61011DR00-029-G | RES,2.2KOhm,+/-1%,1/16W,G,SMD0402 | VISHAY ENTER TECHNO LOGY.INC | CRCW04022K20FKED | G | PWA BOM | In New BOM |
|  | R59,R61,R73,R75,R87,R89,R116,R117,R118,R128,R129,R130,R155,R157,R158,R166,R167,R168,R180,R181,R182,R192,R193,R194 | 24 | 61011DR00-017-G | RES,2.2KOhm,+/-1%,1/16W,G,SMD0402 | KOA SPEER ELECTRONICS, INC. | RK73H1ETTP2201F | N | PWA BOM | In Old BOM |
|  |  |  | 61011DR00-012-G | RES,2.2KOhm,+/-1%,1/16W,G,SMD0402 | WALSIN | WR04X2201FTL | G | PWA BOM | In Old BOM |
|  |  |  | 61011DR00-011-G | RES,2.2KOhm,+/-1%,1/16W,G,SMD0402 | YAGEO | RC0402FR-072K2L | G | PWA BOM | In Old BOM |
|  |  |  | 61011DR00-044-G | RES,2.2KOhm,+/-1%,1/16W,G,SMD0402 | TA-I | RM04FTN2201 | G | PWA BOM | In Old BOM |
|  |  |  | 61011DR00-029-G | RES,2.2KOhm,+/-1%,1/16W,G,SMD0402 | VISHAY | CRCW04022K20FKED | G | PWA BOM | In Old BOM |
| 55 | R98,R99,R106,R107,R110,R112 | 6 | 61011DG01-017-G | RES,10KOhm,+/-1%,1/20W,G,SMD0201 | KOA SPEER ELECTRONICS, INC. | RK73H1HTTC1002F | N | PWA BOM | In New BOM |
|  |  |  | 61011DG00-012-G | RES,10KOhm,+/-1%,1/20W,G,SMD0201 | WALSIN TECHNOLOGY CORPORATION | WR02X1002FAL | G | PWA BOM | In New BOM |
|  |  |  | 61011DG00-011-G | RES,10KOhm,+/-1%,1/20W,G,SMD0201 | YAGEO CORPORATION COMPONENT | RC0201FR-0710KL | G | PWA BOM | In New BOM |
|  |  |  | 61011DG00-044-G | RES,10KOhm,+/-1%,1/20W,G,SMD0201 | TA-I TECHNOLOGY CO., LTD. | RM02FTN1002 | G | PWA BOM | In New BOM |
|  | R98,R99,R106,R107,R110,R112 | 6 | 61011DG01-017-G | RES,10KOhm,+/-1%,1/20W,G,SMD0201 | KOA SPEER ELECTRONICS, INC. | RK73H1HTTC1002F | N | PWA BOM | In Old BOM |
|  |  |  | 61011DG00-012-G | RES,10KOhm,+/-1%,1/20W,G,SMD0201 | WALSIN | WR02X1002FAL | G | PWA BOM | In Old BOM |
|  |  |  | 61011DG00-011-G | RES,10KOhm,+/-1%,1/20W,G,SMD0201 | YAGEO | RC0201FR-0710KL | G | PWA BOM | In Old BOM |
|  |  |  | 61011DG00-044-G | RES,10KOhm,+/-1%,1/20W,G,SMD0201 | TA-I | RM02FTN1002 | G | PWA BOM | In Old BOM |
| 56 | R100,R102 | 2 | 61011DL01-017-G | RES,1KOhm,+/-1%,1/20W,G,SMD0201 | KOA SPEER ELECTRONICS, INC. | RK73H1HTTC1001F | N | PWA BOM | In New BOM |
|  |  |  | 61011DL00-012-G | RES,1KOhm,+/-1%,1/20W,G,SMD0201 | WALSIN TECHNOLOGY CORPORATION | WR02X1001FAL | G | PWA BOM | In New BOM |
|  |  |  | 61011DL00-011-G | RES,1KOhm,+/-1%,1/20W,G,SMD0201 | YAGEO CORPORATION COMPONENT | RC0201FR-071KL | G | PWA BOM | In New BOM |
|  |  |  | 61011DL00-044-G | RES,1KOhm,+/-1%,1/20W,G,SMD0201 | TA-I TECHNOLOGY CO., LTD. | RM02FTN1001 | G | PWA BOM | In New BOM |
|  | R100,R102 | 2 | 61011DL01-017-G | RES,1KOhm,+/-1%,1/20W,G,SMD0201 | KOA SPEER ELECTRONICS, INC. | RK73H1HTTC1001F | N | PWA BOM | In Old BOM |
|  |  |  | 61011DL00-012-G | RES,1KOhm,+/-1%,1/20W,G,SMD0201 | WALSIN | WR02X1001FAL | G | PWA BOM | In Old BOM |
|  |  |  | 61011DL00-011-G | RES,1KOhm,+/-1%,1/20W,G,SMD0201 | YAGEO | RC0201FR-071KL | G | PWA BOM | In Old BOM |
|  |  |  | 61011DL00-044-G | RES,1KOhm,+/-1%,1/20W,G,SMD0201 | TA-I | RM02FTN1001 | G | PWA BOM | In Old BOM |
| 57 | R101,R103 | 2 | 61010AN00-017-G | RES,1MOhm,+/-5%,1/16W,G,SMD0402 | KOA SPEER ELECTRONICS, INC. | RK73B1ETTP105J | N | PWA BOM | In New BOM |
|  |  |  | 61010AN00-012-G | RES,1MOhm,+/-5%,1/16W,G,SMD0402 | WALSIN TECHNOLOGY CORPORATION | WR04X105JTL | G | PWA BOM | In New BOM |
|  |  |  | 61010AN00-011-G | RES,1MOhm,+/-5%,1/16W,G,SMD0402 | YAGEO CORPORATION COMPONENT | RC0402JR-071ML | G | PWA BOM | In New BOM |
|  |  |  | 61010AN00-044-G | RES,1MOhm,+/-5%,1/16W,G,SMD0402 | TA-I TECHNOLOGY CO., LTD. | RM04JTN105 | G | PWA BOM | In New BOM |
|  | R101,R103 | 2 | 61010AN00-017-G | RES,1MOhm,+/-5%,1/16W,G,SMD0402 | KOA SPEER ELECTRONICS, INC. | RK73B1ETTP105J | N | PWA BOM | In Old BOM |
|  |  |  | 61010AN00-012-G | RES,1MOhm,+/-5%,1/16W,G,SMD0402 | WALSIN | WR04X105JTL | G | PWA BOM | In Old BOM |
|  |  |  | 61010AN00-011-G | RES,1MOhm,+/-5%,1/16W,G,SMD0402 | YAGEO | RC0402JR-071ML | G | PWA BOM | In Old BOM |
|  |  |  | 61010AN00-044-G | RES,1MOhm,+/-5%,1/16W,G,SMD0402 | TA-I | RM04JTN105 | G | PWA BOM | In Old BOM |
| 58 | R104,R105 | 2 | 610132800-017-G | RES,1.54KOhm,+/-1%,1/20W,G,SMD0201 | KOA SPEER ELECTRONICS, INC. | RK73H1HTTC1541F | N | PWA BOM | In New BOM |
|  |  |  | 610132800-012-G | RES,1.54KOhm,+/-1%,1/20W,G,SMD0201 | WALSIN TECHNOLOGY CORPORATION | WR02X1541FAL | G | PWA BOM | In New BOM |
|  |  |  | 610132800-044-G | RES,1.54KOhm,+/-1%,1/20W,G,SMD0201 | TA-I TECHNOLOGY CO., LTD. | RM02FTN1541 | G | PWA BOM | In New BOM |
|  | R104,R105 | 2 | 610132800-017-G | RES,1.54KOhm,+/-1%,1/20W,G,SMD0201 | KOA SPEER ELECTRONICS, INC. | RK73H1HTTC1541F | N | PWA BOM | In Old BOM |
|  |  |  | 610132800-012-G | RES,1.54KOhm,+/-1%,1/20W,G,SMD0201 | WALSIN | WR02X1541FAL | G | PWA BOM | In Old BOM |
|  |  |  | 610132800-044-G | RES,1.54KOhm,+/-1%,1/20W,G,SMD0201 | TA-I | RM02FTN1541 | G | PWA BOM | In Old BOM |
| 59 | R108,R109 | 2 | 610113T00-017-G | RES,13.7KOhm,+/-1%,1/16W,G,SMD0402 | KOA SPEER ELECTRONICS, INC. | RK73H1ETTP1372F | N | PWA BOM | In New BOM |
|  |  |  | 610113T00-012-G | RES,13.7KOhm,+/-1%,1/16W,G,SMD0402 | WALSIN TECHNOLOGY CORPORATION | WR04X1372FTL | G | PWA BOM | In New BOM |
|  |  |  | 610113T00-011-G | RES,13.7KOhm,+/-1%,1/16W,G,SMD0402 | YAGEO CORPORATION COMPONENT | RC0402FR-0713K7L | G | PWA BOM | In New BOM |
|  |  |  | 610113T00-044-G | RES,13.7KOhm,+/-1%,1/16W,G,SMD0402 | TA-I TECHNOLOGY CO., LTD. | RM04FTN1372 | G | PWA BOM | In New BOM |
|  | R108,R109 | 2 | 610113T00-017-G | RES,13.7KOhm,+/-1%,1/16W,G,SMD0402 | KOA SPEER ELECTRONICS, INC. | RK73H1ETTP1372F | N | PWA BOM | In Old BOM |
|  |  |  | 610113T00-012-G | RES,13.7KOhm,+/-1%,1/16W,G,SMD0402 | WALSIN | WR04X1372FTL | G | PWA BOM | In Old BOM |
|  |  |  | 610113T00-011-G | RES,13.7KOhm,+/-1%,1/16W,G,SMD0402 | YAGEO | RC0402FR-0713K7L | G | PWA BOM | In Old BOM |
|  |  |  | 610113T00-044-G | RES,13.7KOhm,+/-1%,1/16W,G,SMD0402 | TA-I | RM04FTN1372 | G | PWA BOM | In Old BOM |
| 60 | R111,R113 | 2 | 61011KY00-017-G | RES,3.83KOhm,+/-1%,1/16W,G,SMD0402 | KOA SPEER ELECTRONICS, INC. | RK73H1ETTP3831F | N | PWA BOM | In New BOM |
|  |  |  | 61011KY00-012-G | RES,3.83KOhm,+/-1%,1/16W,G,SMD0402 | WALSIN TECHNOLOGY CORPORATION | WR04X3831FTL | G | PWA BOM | In New BOM |
|  |  |  | 61011KY00-011-G | RES,3.83KOhm,+/-1%,1/16W,G,SMD0402 | YAGEO CORPORATION COMPONENT | RC0402FR-073K83L | G | PWA BOM | In New BOM |
|  |  |  | 61011KY00-044-G | RES,3.83KOhm,+/-1%,1/16W,G,SMD0402 | TA-I TECHNOLOGY CO., LTD. | RM04FTN3831 | G | PWA BOM | In New BOM |
|  |  |  | 61011KY00-029-G | RES,3.83KOhm,+/-1%,1/16W,G,SMD0402 | VISHAY ENTER TECHNO LOGY.INC | CRCW04023K83FKED | G | PWA BOM | In New BOM |
|  | R111,R113 | 2 | 61011KY00-017-G | RES,3.83KOhm,+/-1%,1/16W,G,SMD0402 | KOA SPEER ELECTRONICS, INC. | RK73H1ETTP3831F | N | PWA BOM | In Old BOM |
|  |  |  | 61011KY00-012-G | RES,3.83KOhm,+/-1%,1/16W,G,SMD0402 | WALSIN | WR04X3831FTL | G | PWA BOM | In Old BOM |
|  |  |  | 61011KY00-011-G | RES,3.83KOhm,+/-1%,1/16W,G,SMD0402 | YAGEO | RC0402FR-073K83L | G | PWA BOM | In Old BOM |
|  |  |  | 61011KY00-044-G | RES,3.83KOhm,+/-1%,1/16W,G,SMD0402 | TA-I | RM04FTN3831 | G | PWA BOM | In Old BOM |
|  |  |  | 61011KY00-029-G | RES,3.83KOhm,+/-1%,1/16W,G,SMD0402 | VISHAY | CRCW04023K83FKED | G | PWA BOM | In Old BOM |
| 61 | R120,R122,R132,R134,R160,R163,R173,R175,R184,R186,R196,R198,R500,R1484,R1779 | 15 | 61100LR00-017-G | RES,100 Ohm,+/-1%,1/16W,G,SMD0402 | KOA SPEER ELECTRONICS, INC. | RN731ETTP1000F50 |  | PWA BOM | In New BOM |
|  |  |  | 61100LR00-012-G | RES,100 Ohm,+/-1%,1/16W,G,SMD0402 | WALSIN TECHNOLOGY CORPORATION | WF04T1000FTL | G | PWA BOM | In New BOM |
|  |  |  | 61100LR01-011-G | RES,100 Ohm,+/-1%,1/16W,G,SMD0402 | YAGEO CORPORATION COMPONENT | RT0402FRE07100RL | G | PWA BOM | In New BOM |
|  |  |  | 61100LR00-044-G | RES,100 Ohm,+/-1%,1/16W,G,SMD0402 | TA-I TECHNOLOGY CO., LTD. | RB04FTS1000 | G | PWA BOM | In New BOM |
|  | R120,R122,R132,R134,R160,R163,R173,R175,R184,R186,R196,R198,R500,R1484,R1779 | 15 | 61100LR00-017-G | RES,100 Ohm,+/-1%,1/16W,G,SMD0402 | KOA SPEER ELECTRONICS, INC. | RN731ETTP1000F50 |  | PWA BOM | In Old BOM |
|  |  |  | 61100LR00-012-G | RES,100 Ohm,+/-1%,1/16W,G,SMD0402 | WALSIN | WF04T1000FTL | G | PWA BOM | In Old BOM |
|  |  |  | 61100LR01-011-G | RES,100 Ohm,+/-1%,1/16W,G,SMD0402 | YAGEO | RT0402FRE07100RL | G | PWA BOM | In Old BOM |
|  |  |  | 61100LR00-044-G | RES,100 Ohm,+/-1%,1/16W,G,SMD0402 | TA-I | RB04FTS1000 | G | PWA BOM | In Old BOM |
| 62 | R124,R125,R136,R137,R164,R165,R176,R177,R188,R189,R200,R201 | 12 | 61011CY00-017-G | RES,5.6KOhm,+/-1%,1/16W,G,SMD0402 | KOA SPEER ELECTRONICS, INC. | RK73H1ETTP5601F | N | PWA BOM | In New BOM |
|  |  |  | 61011CY00-012-G | RES,5.6KOhm,+/-1%,1/16W,G,SMD0402 | WALSIN TECHNOLOGY CORPORATION | WR04X5601FTL | G | PWA BOM | In New BOM |
|  |  |  | 61011CY00-011-G | RES,5.6KOhm,+/-1%,1/16W,G,SMD0402 | YAGEO CORPORATION COMPONENT | RC0402FR-075K6L | G | PWA BOM | In New BOM |
|  |  |  | 61011CY00-044-G | RES,5.6KOhm,+/-1%,1/16W,G,SMD0402 | TA-I TECHNOLOGY CO., LTD. | RM04FTN5601 | G | PWA BOM | In New BOM |
|  |  |  | 61011CY00-029-G | RES,5.6KOhm,+/-1%,1/16W,G,SMD0402 | VISHAY ENTER TECHNO LOGY.INC | CRCW04025K60FKED | G | PWA BOM | In New BOM |
|  | R124,R125,R136,R137,R164,R165,R176,R177,R188,R189,R200,R201 | 12 | 61011CY00-017-G | RES,5.6KOhm,+/-1%,1/16W,G,SMD0402 | KOA SPEER ELECTRONICS, INC. | RK73H1ETTP5601F | N | PWA BOM | In Old BOM |
|  |  |  | 61011CY00-012-G | RES,5.6KOhm,+/-1%,1/16W,G,SMD0402 | WALSIN | WR04X5601FTL | G | PWA BOM | In Old BOM |
|  |  |  | 61011CY00-011-G | RES,5.6KOhm,+/-1%,1/16W,G,SMD0402 | YAGEO | RC0402FR-075K6L | G | PWA BOM | In Old BOM |
|  |  |  | 61011CY00-044-G | RES,5.6KOhm,+/-1%,1/16W,G,SMD0402 | TA-I | RM04FTN5601 | G | PWA BOM | In Old BOM |
|  |  |  | 61011CY00-029-G | RES,5.6KOhm,+/-1%,1/16W,G,SMD0402 | VISHAY | CRCW04025K60FKED | G | PWA BOM | In Old BOM |
| 63 | R142,R143,R144,R145,R146,R147,R148,R149,R150,R151,R152,R153 | 12 | 61011QD00-017-G | RES,330 Ohm,+/-1%,1/16W,G,SMD0402 | KOA SPEER ELECTRONICS, INC. | RK73H1ETTP3300F | N | PWA BOM | In New BOM |
|  |  |  | 61011QD00-012-G | RES,330 Ohm,+/-1%,1/16W,G,SMD0402 | WALSIN TECHNOLOGY CORPORATION | WR04X3300FTL | G | PWA BOM | In New BOM |
|  |  |  | 61011QD00-011-G | RES,330 Ohm,+/-1%,1/16W,G,SMD0402 | YAGEO CORPORATION COMPONENT | RC0402FR-07330RL | G | PWA BOM | In New BOM |
|  |  |  | 61011QD00-044-G | RES,330 Ohm,+/-1%,1/16W,G,SMD0402 | TA-I TECHNOLOGY CO., LTD. | RM04FTN3300 | G | PWA BOM | In New BOM |
|  | R142,R143,R144,R145,R146,R147,R148,R149,R150,R151,R152,R153 | 12 | 61011QD00-017-G | RES,330 Ohm,+/-1%,1/16W,G,SMD0402 | KOA SPEER ELECTRONICS, INC. | RK73H1ETTP3300F | N | PWA BOM | In Old BOM |
|  |  |  | 61011QD00-012-G | RES,330 Ohm,+/-1%,1/16W,G,SMD0402 | WALSIN | WR04X3300FTL | G | PWA BOM | In Old BOM |
|  |  |  | 61011QD00-011-G | RES,330 Ohm,+/-1%,1/16W,G,SMD0402 | YAGEO | RC0402FR-07330RL | G | PWA BOM | In Old BOM |
|  |  |  | 61011QD00-044-G | RES,330 Ohm,+/-1%,1/16W,G,SMD0402 | TA-I | RM04FTN3300 | G | PWA BOM | In Old BOM |
| 64 | R202 | 1 | 61011H500-017-G | RES,22 Ohm,+/-1%,1/16W,G,SMD0402 | KOA SPEER ELECTRONICS, INC. | RK73H1ETTP22R0F | N | PWA BOM | In New BOM |
|  |  |  | 61011H500-012-G | RES,22 Ohm,+/-1%,1/16W,G,SMD0402 | WALSIN TECHNOLOGY CORPORATION | WR04X22R0FTL | G | PWA BOM | In New BOM |
|  |  |  | 61011H500-011-G | RES,22 Ohm,+/-1%,1/16W,G,SMD0402 | YAGEO CORPORATION COMPONENT | RC0402FR-0722RL | G | PWA BOM | In New BOM |
|  |  |  | 61011H500-044-G | RES,22 Ohm,+/-1%,1/16W,G,SMD0402 | TA-I TECHNOLOGY CO., LTD. | RM04FTN22R0 | G | PWA BOM | In New BOM |
|  |  |  | 61011H500-024-G | RES,22 Ohm,+/-1%,1/16W,G,SMD0402 | PANASONIC INDUSTRIAL CO.,LTD. | ERJ2RKF22R0X | G | PWA BOM | In New BOM |
|  | R202 | 1 | 61011H500-017-G | RES,22 Ohm,+/-1%,1/16W,G,SMD0402 | KOA SPEER ELECTRONICS, INC. | RK73H1ETTP22R0F | N | PWA BOM | In Old BOM |
|  |  |  | 61011H500-012-G | RES,22 Ohm,+/-1%,1/16W,G,SMD0402 | WALSIN | WR04X22R0FTL | G | PWA BOM | In Old BOM |
|  |  |  | 61011H500-011-G | RES,22 Ohm,+/-1%,1/16W,G,SMD0402 | YAGEO | RC0402FR-0722RL | G | PWA BOM | In Old BOM |
|  |  |  | 61011H500-044-G | RES,22 Ohm,+/-1%,1/16W,G,SMD0402 | TA-I | RM04FTN22R0 | G | PWA BOM | In Old BOM |
|  |  |  | 61011H500-024-G | RES,22 Ohm,+/-1%,1/16W,G,SMD0402 | PANASONIC | ERJ2RKF22R0X | G | PWA BOM | In Old BOM |
| 65 | R203,R1770,R1771 | 3 | 61010JY00-017-G | RES,220 Ohm,+/-5%,1/16W,G,SMD0402 | KOA SPEER ELECTRONICS, INC. | RK73B1ETTP221J | N | PWA BOM | In New BOM |
|  |  |  | 61010JY00-012-G | RES,220 Ohm,+/-5%,1/16W,G,SMD0402 | WALSIN TECHNOLOGY CORPORATION | WR04X221JTL | G | PWA BOM | In New BOM |
|  |  |  | 61010JY00-011-G | RES,220 Ohm,+/-5%,1/16W,G,SMD0402 | YAGEO CORPORATION COMPONENT | RC0402JR-07220RL | G | PWA BOM | In New BOM |
|  |  |  | 61010JY00-044-G | RES,220 Ohm,+/-5%,1/16W,G,SMD0402 | TA-I TECHNOLOGY CO., LTD. | RM04JTN221 | G | PWA BOM | In New BOM |
|  | R203,R1770,R1771 | 3 | 61010JY00-017-G | RES,220 Ohm,+/-5%,1/16W,G,SMD0402 | KOA SPEER ELECTRONICS, INC. | RK73B1ETTP221J | N | PWA BOM | In Old BOM |
|  |  |  | 61010JY00-012-G | RES,220 Ohm,+/-5%,1/16W,G,SMD0402 | WALSIN | WR04X221JTL | G | PWA BOM | In Old BOM |
|  |  |  | 61010JY00-011-G | RES,220 Ohm,+/-5%,1/16W,G,SMD0402 | YAGEO | RC0402JR-07220RL | G | PWA BOM | In Old BOM |
|  |  |  | 61010JY00-044-G | RES,220 Ohm,+/-5%,1/16W,G,SMD0402 | TA-I | RM04JTN221 | G | PWA BOM | In Old BOM |
| 66 | R1480 | 1 | 61012LR00-017-G | RES,1KOhm,+/-0.5%,1/16W,G,SMD0402 | KOA SPEER ELECTRONICS, INC. | RK73H1ETTP1001D | N | PWA BOM | In New BOM |
|  |  |  | 61012LR00-012-G | RES,1KOhm,+/-0.5%,1/16W,G,SMD0402 | WALSIN TECHNOLOGY CORPORATION | WF04H1001DTL |  | PWA BOM | In New BOM |
|  |  |  | 61012LR00-011-G | RES,1KOhm,+/-0.5%,1/16W,G,SMD0402 | YAGEO CORPORATION COMPONENT | RC0402DR-071KL |  | PWA BOM | In New BOM |
|  |  |  | 61012LR00-044-G | RES,1KOhm,+/-0.5%,1/16W,G,SMD0402 | TA-I TECHNOLOGY CO., LTD. | RM04DTN1001 |  | PWA BOM | In New BOM |
|  | R1480 | 1 | 61012LR00-017-G | RES,1KOhm,+/-0.5%,1/16W,G,SMD0402 | KOA SPEER ELECTRONICS, INC. | RK73H1ETTP1001D | N | PWA BOM | In Old BOM |
|  |  |  | 61012LR00-012-G | RES,1KOhm,+/-0.5%,1/16W,G,SMD0402 | WALSIN | WF04H1001DTL |  | PWA BOM | In Old BOM |
|  |  |  | 61012LR00-011-G | RES,1KOhm,+/-0.5%,1/16W,G,SMD0402 | YAGEO | RC0402DR-071KL |  | PWA BOM | In Old BOM |
|  |  |  | 61012LR00-044-G | RES,1KOhm,+/-0.5%,1/16W,G,SMD0402 | TA-I | RM04DTN1001 |  | PWA BOM | In Old BOM |
| 67 | R1487 | 1 | 610112J00-017-G | RES,200 Ohm,+/-1%,1/16W,G,SMD0402 | KOA SPEER ELECTRONICS, INC. | RK73H1ETTP2000F | N | PWA BOM | In New BOM |
|  |  |  | 610112J00-012-G | RES,200 Ohm,+/-1%,1/16W,G,SMD0402 | WALSIN TECHNOLOGY CORPORATION | WR04X2000FTL |  | PWA BOM | In New BOM |
|  |  |  | 610112J00-011-G | RES,200 Ohm,+/-1%,1/16W,G,SMD0402 | YAGEO CORPORATION COMPONENT | RC0402FR-07200RL |  | PWA BOM | In New BOM |
|  |  |  | 610112J00-044-G | RES,200 Ohm,+/-1%,1/16W,G,SMD0402 | TA-I TECHNOLOGY CO., LTD. | RM04FTN2000 |  | PWA BOM | In New BOM |
|  |  |  | 610112J00-029-G | RES,200 Ohm,+/-1%,1/16W,G,SMD0402 | VISHAY ENTER TECHNO LOGY.INC | CRCW0402200RFKED |  | PWA BOM | In New BOM |
|  |  |  | 610112J00-024-G | RES,200 Ohm,+/-1%,1/16W,G,SMD0402 | PANASONIC INDUSTRIAL CO.,LTD. | ERJ2RKF2000X |  | PWA BOM | In New BOM |
|  | R1487 | 1 | 610112J00-017-G | RES,200 Ohm,+/-1%,1/16W,G,SMD0402 | KOA SPEER ELECTRONICS, INC. | RK73H1ETTP2000F | N | PWA BOM | In Old BOM |
|  |  |  | 610112J00-012-G | RES,200 Ohm,+/-1%,1/16W,G,SMD0402 | WALSIN | WR04X2000FTL |  | PWA BOM | In Old BOM |
|  |  |  | 610112J00-011-G | RES,200 Ohm,+/-1%,1/16W,G,SMD0402 | YAGEO | RC0402FR-07200RL |  | PWA BOM | In Old BOM |
|  |  |  | 610112J00-044-G | RES,200 Ohm,+/-1%,1/16W,G,SMD0402 | TA-I | RM04FTN2000 |  | PWA BOM | In Old BOM |
|  |  |  | 610112J00-029-G | RES,200 Ohm,+/-1%,1/16W,G,SMD0402 | VISHAY ENTER TECHNO LOGY.INC | CRCW0402200RFKED |  | PWA BOM | In Old BOM |
|  |  |  | 610112J00-024-G | RES,200 Ohm,+/-1%,1/16W,G,SMD0402 | PANASONIC INDUSTRIAL CO.,LTD. | ERJ2RKF2000X |  | PWA BOM | In Old BOM |
| 68 | R1488 | 1 | 61100LQ00-017-G | RES,20KOhm,+/-1%,1/16W,G,SMD0402 | KOA SPEER ELECTRONICS, INC. | RN731ETTP2002F50 |  | PWA BOM | In New BOM |
|  |  |  | 61100LQ00-012-G | RES,20KOhm,+/-1%,1/16W,G,SMD0402 | WALSIN TECHNOLOGY CORPORATION | WF04T2002FTL | G | PWA BOM | In New BOM |
|  |  |  | 61100LQ00-011-G | RES,20KOhm,+/-1%,1/16W,G,SMD0402 | YAGEO CORPORATION COMPONENT | RT0402FRE0720KL | G | PWA BOM | In New BOM |
|  |  |  | 61100LQ00-044-G | RES,20KOhm,+/-1%,1/16W,G,SMD0402 | TA-I TECHNOLOGY CO., LTD. | RB04FTS2002 | G | PWA BOM | In New BOM |
|  | R1488 | 1 | 61100LQ00-017-G | RES,20KOhm,+/-1%,1/16W,G,SMD0402 | KOA SPEER ELECTRONICS, INC. | RN731ETTP2002F50 |  | PWA BOM | In Old BOM |
|  |  |  | 61100LQ00-012-G | RES,20KOhm,+/-1%,1/16W,G,SMD0402 | WALSIN | WF04T2002FTL | G | PWA BOM | In Old BOM |
|  |  |  | 61100LQ00-011-G | RES,20KOhm,+/-1%,1/16W,G,SMD0402 | YAGEO | RT0402FRE0720KL | G | PWA BOM | In Old BOM |
|  |  |  | 61100LQ00-044-G | RES,20KOhm,+/-1%,1/16W,G,SMD0402 | TA-I | RB04FTS2002 | G | PWA BOM | In Old BOM |
| 69 | R1493 | 1 | 61011LF00-017-G | RES,499KOhm,+/-1%,1/16W,G,SMD0402 | KOA SPEER ELECTRONICS, INC. | RK73H1ETTP4993F | N | PWA BOM | In New BOM |
|  |  |  | 61011LF00-012-G | RES,499KOhm,+/-1%,1/16W,G,SMD0402 | WALSIN TECHNOLOGY CORPORATION | WR04X4993FTL |  | PWA BOM | In New BOM |
|  |  |  | 61011LF00-011-G | RES,499KOhm,+/-1%,1/16W,G,SMD0402 | YAGEO CORPORATION COMPONENT | RC0402FR-07499KL |  | PWA BOM | In New BOM |
|  |  |  | 61011LF00-044-G | RES,499KOhm,+/-1%,1/16W,G,SMD0402 | TA-I TECHNOLOGY CO., LTD. | RM04FTN4993 |  | PWA BOM | In New BOM |
|  | R1493 | 1 | 61011LF00-017-G | RES,499KOhm,+/-1%,1/16W,G,SMD0402 | KOA SPEER ELECTRONICS, INC. | RK73H1ETTP4993F | N | PWA BOM | In Old BOM |
|  |  |  | 61011LF00-012-G | RES,499KOhm,+/-1%,1/16W,G,SMD0402 | WALSIN | WR04X4993FTL |  | PWA BOM | In Old BOM |
|  |  |  | 61011LF00-011-G | RES,499KOhm,+/-1%,1/16W,G,SMD0402 | YAGEO | RC0402FR-07499KL |  | PWA BOM | In Old BOM |
|  |  |  | 61011LF00-044-G | RES,499KOhm,+/-1%,1/16W,G,SMD0402 | TA-I | RM04FTN4993 |  | PWA BOM | In Old BOM |
| 70 | R1809,R1810,R1812 | 3 | 61011CM00-017-G | RES,69.8KOhm,+/-1%,1/16W,G,SMD0402 | KOA SPEER ELECTRONICS, INC. | RK73H1ETTP6982F | N | PWA BOM | In New BOM |
|  |  |  | 61011CM00-012-G | RES,69.8KOhm,+/-1%,1/16W,G,SMD0402 | WALSIN TECHNOLOGY CORPORATION | WR04X6982FTL | G | PWA BOM | In New BOM |
|  |  |  | 61011CM00-011-G | RES,69.8KOhm,+/-1%,1/16W,G,SMD0402 | YAGEO CORPORATION COMPONENT | RC0402FR-0769K8L | G | PWA BOM | In New BOM |
|  |  |  | 61011CM00-044-G | RES,69.8KOhm,+/-1%,1/16W,G,SMD0402 | TA-I TECHNOLOGY CO., LTD. | RM04FTN6982 | G | PWA BOM | In New BOM |
|  | R1809,R1810,R1812 | 3 | 61011CM00-017-G | RES,69.8KOhm,+/-1%,1/16W,G,SMD0402 | KOA SPEER ELECTRONICS, INC. | RK73H1ETTP6982F | N | PWA BOM | In Old BOM |
|  |  |  | 61011CM00-012-G | RES,69.8KOhm,+/-1%,1/16W,G,SMD0402 | WALSIN | WR04X6982FTL | G | PWA BOM | In Old BOM |
|  |  |  | 61011CM00-011-G | RES,69.8KOhm,+/-1%,1/16W,G,SMD0402 | YAGEO | RC0402FR-0769K8L | G | PWA BOM | In Old BOM |
|  |  |  | 61011CM00-044-G | RES,69.8KOhm,+/-1%,1/16W,G,SMD0402 | TA-I | RM04FTN6982 | G | PWA BOM | In Old BOM |
| 71 | R1811 | 1 | 610113W00-017-G | RES,12.1KOhm,+/-1%,1/16W,G,SMD0402 | KOA SPEER ELECTRONICS, INC. | RK73H1ETTP1212F | N | PWA BOM | In New BOM |
|  |  |  | 610113W00-012-G | RES,12.1KOhm,+/-1%,1/16W,G,SMD0402 | WALSIN TECHNOLOGY CORPORATION | WR04X1212FTL | G | PWA BOM | In New BOM |
|  |  |  | 610113W00-011-G | RES,12.1KOhm,+/-1%,1/16W,G,SMD0402 | YAGEO CORPORATION COMPONENT | RC0402FR-0712K1L | G | PWA BOM | In New BOM |
|  |  |  | 610113W00-044-G | RES,12.1KOhm,+/-1%,1/16W,G,SMD0402 | TA-I TECHNOLOGY CO., LTD. | RM04FTN1212 | G | PWA BOM | In New BOM |
|  | R1811 | 1 | 610113W00-017-G | RES,12.1KOhm,+/-1%,1/16W,G,SMD0402 | KOA SPEER ELECTRONICS, INC. | RK73H1ETTP1212F | N | PWA BOM | In Old BOM |
|  |  |  | 610113W00-012-G | RES,12.1KOhm,+/-1%,1/16W,G,SMD0402 | WALSIN | WR04X1212FTL | G | PWA BOM | In Old BOM |
|  |  |  | 610113W00-011-G | RES,12.1KOhm,+/-1%,1/16W,G,SMD0402 | YAGEO | RC0402FR-0712K1L | G | PWA BOM | In Old BOM |
|  |  |  | 610113W00-044-G | RES,12.1KOhm,+/-1%,1/16W,G,SMD0402 | TA-I | RM04FTN1212 | G | PWA BOM | In Old BOM |
| 72 | R1815,R1816,R1817,R1818 | 4 | 61100LV00-017-G | RES,10KOhm,+/-1%,1/16W,G,SMD0402 | KOA SPEER ELECTRONICS, INC. | RN731ETTP1002F50 |  | PWA BOM | In New BOM |
|  |  |  | 61100LV00-012-G | RES,10KOhm,+/-1%,1/16W,G,SMD0402 | WALSIN TECHNOLOGY CORPORATION | WF04T1002FTL |  | PWA BOM | In New BOM |
|  |  |  | 61100LV00-011-G | RES,10KOhm,+/-1%,1/16W,G,SMD0402 | YAGEO CORPORATION COMPONENT | RT0402FRE0710KL |  | PWA BOM | In New BOM |
|  |  |  | 61100LV00-044-G | RES,10KOhm,+/-1%,1/16W,G,SMD0402 | TA-I TECHNOLOGY CO., LTD. | RB04FTS1002 |  | PWA BOM | In New BOM |
|  | R1815,R1816,R1817,R1818 | 4 | 61100LV00-017-G | RES,10KOhm,+/-1%,1/16W,G,SMD0402 | KOA SPEER ELECTRONICS, INC. | RN731ETTP1002F50 |  | PWA BOM | In Old BOM |
|  |  |  | 61100LV00-012-G | RES,10KOhm,+/-1%,1/16W,G,SMD0402 | WALSIN | WF04T1002FTL |  | PWA BOM | In Old BOM |
|  |  |  | 61100LV00-011-G | RES,10KOhm,+/-1%,1/16W,G,SMD0402 | YAGEO | RT0402FRE0710KL |  | PWA BOM | In Old BOM |
|  |  |  | 61100LV00-044-G | RES,10KOhm,+/-1%,1/16W,G,SMD0402 | TA-I | RB04FTS1002 |  | PWA BOM | In Old BOM |
| 73 | U_FPDB_FRU | 1 | 41040HW00-191-G | EEPROM,AT24C02D-SSHM-T,1.7~3.6V,2K,I2C,G,SOIC-8,SMD | ATMEL CORPORATION | AT24C02D-SSHM-T |  | PWA BOM | In New BOM |
|  |  |  | 410401W00-214-G | EEPROM,M24C02-WMN6TP,2.5~5.5V,256*8,I2C,G,SOIC-8,SMD | ST MICRO ELECTRONICS,INC | M24C02-WMN6TP | G | PWA BOM | In New BOM |
|  |  |  | 41040CW00-232-G | EEPROM,24AA024-I/SN,1.7~5.5V,2K,I2C,G,SOIC-8,SMD | MICROCHIP TECHNOLOGY INC | 24AA024-I/SN | G | PWA BOM | In New BOM |
|  | U_FPDB_FRU | 1 | 41040HW00-191-G | EEPROM,AT24C02D-SSHM-T,1.7~3.6V,2K,I2C,G,SOIC-8,SMD | ATMEL CORPORATION | AT24C02D-SSHM-T |  | PWA BOM | In Old BOM |
|  |  |  | 410401W00-214-G | EEPROM,M24C02-WMN6TP,2.5~5.5V,256*8,I2C,G,SOIC-8,SMD | ST | M24C02-WMN6TP | G | PWA BOM | In Old BOM |
|  |  |  | 41040CW00-232-G | EEPROM,24AA024-I/SN,1.7~5.5V,2K,I2C,G,SOIC-8,SMD | MICROCHIP | 24AA024-I/SN | G | PWA BOM | In Old BOM |
| 74 | U_TMP_R | 1 | 320403K00-183-G | IC,Temp Sensor,TMP75AIDR,3°C,G,SOIC-8,SMD | TEXAS INSTRUMENTS | TMP75AIDR | N | PWA BOM | In New BOM |
|  |  |  | 320404J00-190-G | IC,Temp Sensor,ADT75ARZ-REEL,1°C,G,SOIC-8,SMD | ANALOG DEVICES INC | ADT75ARZ-REEL |  | PWA BOM | In New BOM |
|  |  |  | 320403Q00-173-G | IC,Temp Sensor,DS75S+T&R,3°C,G,SO-8,SMD | MAXIM INTEGRATED PRODUCTS, INC. | DS75S+T&R |  | PWA BOM | In New BOM |
|  |  |  | 320405300-214-G | IC,Temp Sensor,STLM75M2F,±0.5°C,G,SO-8,SMD | ST MICRO ELECTRONICS,INC | STLM75M2F |  | PWA BOM | In New BOM |
|  |  |  | 32040SL00-223-G | IC,Temperature Sensor,NCT75DR2G,G,SOIC-8,SMD | ON SEMICONDUCTOR CORP | NCT75DR2G |  | PWA BOM | In New BOM |
|  |  |  | 32040FL00-031-G | IC,Temperature Sensor,LM75BD,G,SO-8,SMD | NXP SEMICONDUCTORS | LM75BD |  | PWA BOM | In New BOM |
|  | U_TMP_R | 1 | 320403K00-183-G | IC,Temp Sensor,TMP75AIDR,3°C,G,SOIC-8,SMD | TEXAS INSTRUMENTS | TMP75AIDR | N | PWA BOM | In Old BOM |
|  |  |  | 320404J00-190-G | IC,Temp Sensor,ADT75ARZ-REEL,1°C,G,SOIC-8,SMD | ANALOG DEVICES INC | ADT75ARZ-REEL |  | PWA BOM | In Old BOM |
|  |  |  | 320403Q00-173-G | IC,Temp Sensor,DS75S+T&R,3°C,G,SO-8,SMD | MAXIM | DS75S+T&R |  | PWA BOM | In Old BOM |
|  |  |  | 320405300-214-G | IC,Temp Sensor,STLM75M2F,±0.5°C,G,SO-8,SMD | ST | STLM75M2F |  | PWA BOM | In Old BOM |
|  |  |  | 32040SL00-223-G | IC,Temperature Sensor,NCT75DR2G,G,SOIC-8,SMD | ON | NCT75DR2G |  | PWA BOM | In Old BOM |
|  |  |  | 32040FL00-031-G | IC,Temperature Sensor,LM75BD,G,SO-8,SMD | NXP | LM75BD |  | PWA BOM | In Old BOM |
| 75 | U1 | 1 | 311004800-031-G | IC,Translator,PCA9617ADPJ,0.8~5.5V,2.2~5.5V,G,TSSOP-8,SMD | NXP SEMICONDUCTORS | PCA9617ADPJ |  | PWA BOM | In New BOM |
|  |  |  | 311004V00-223-G | Logic IC,Translator,PCA9617ADMR2G,Vcca=0.8V~5.5V,Vccb=2.2V~5.5V,102ns,Micro8,8P,G | ON SEMICONDUCTOR CORP | PCA9617ADMR2G | G | PWA BOM | In New BOM |
|  | U1 | 1 | 311004800-031-G | IC,Translator,PCA9617ADPJ,0.8~5.5V,2.2~5.5V,G,TSSOP-8,SMD | NXP SEMICONDUCTORS | PCA9617ADPJ |  | PWA BOM | In Old BOM |
|  |  |  | 311004V00-223-G | Logic IC,Translator,PCA9617ADMR2G,Vcca=0.8V~5.5V,Vccb=2.2V~5.5V,102ns,Micro8,8P,G | ON | PCA9617ADMR2G | G | PWA BOM | In Old BOM |
| 76 | U109 | 1 | 310307T00-031-G | IC,Switch,74CBTLV1G125GV,2.3~3.6V,G,SOT753-5,SMD | NXP SEMICONDUCTORS | 74CBTLV1G125GV |  | PWA BOM | In New BOM |
|  |  |  | 310300D00-183-G | IC,Switch,SN74CBTLV1G125DBVR,2.3~3.6V,G,SOT23-5,SMD | TEXAS INSTRUMENTS | SN74CBTLV1G125DBVR | G | PWA BOM | In New BOM |
|  | U109 | 1 | 310307T00-031-G | IC,Switch,74CBTLV1G125GV,2.3~3.6V,G,SOT753-5,SMD | NXP SEMICONDUCTORS | 74CBTLV1G125GV |  | PWA BOM | In Old BOM |
|  |  |  | SN74CBTLV1G125DBVR | IC,Switch,SN74CBTLV1G125DBVR,2.3~3.6V,G,SOT23-5,SMD | TI | SN74CBTLV1G125DBVR | G | PWA BOM | In Old BOM |
| 77 | J_PS_ON_SW(2-3)1 | 1 | 340612R00-309-G | CONN,Jumper,Bla,2.54mm,G,DIP-2 | SAMTEC INC. | SNT-100-BK-G |  | PWA BOM | In New BOM |
|  |  |  | 34065L900-GRT-G | CONN,jumper,Bla,2.54mm,30u,G,DIP-2 | PINREX TECHNOLOGY CORP. | 201-71-01DB00 | G | PWA BOM | In New BOM |
|  |  |  | 34066N500-600-G | Header&Socket Connector,SJ0520F-A0,Jumper,2,DIP,PBT,2.54mm,3u",Black,G | FOXCONN TECHNOLOGY CO.,LTD. | SJ0520F-A0 | G | PWA BOM | In New BOM |
|  | J_PS_ON_SW(2-3)1 | 1 | 340612R00-309-G | CONN,Jumper,Bla,2.54mm,G,DIP-2 | SAMTEC INC. | SNT-100-BK-G |  | PWA BOM | In Old BOM |
|  |  |  | 34065L900-GRT-G | CONN,jumper,Bla,2.54mm,30u,G,DIP-2 | PINREX TECHNOLOGY CORP. | 201-71-01DB00 | G | PWA BOM | In Old BOM |
|  |  |  | 34066N500-600-G | Header&Socket Connector,SJ0520F-A0,Jumper,2,DIP,PBT,2.54mm,3u",Black,G | FOXCONN TECHNOLOGY CO.,LTD. | SJ0520F-A0 | G | PWA BOM | In Old BOM |
|  |  |  | 34069RA00-637-G | Header&Socket Connector,1200210020,Jumper,2,DIP,PBT,2.54mm,3u",Black,G | LONG SHOUNG CO.,LTD. | 1200210020 | G | PWA BOM | In Old BOM |
| 78 | J_PS_ON1 | 1 | 340600S00-600-G | CONN,Pin Header,1X3,V/T,Bla,2.54mm,15u,G,DIP-3 | FOXCONN TECHNOLOGY CO.,LTD. | HB1103V |  | PWA BOM | In New BOM |
|  |  |  | 34060WK00-317-G | CONN.Pin Header,1X3,V/T,Bla,2.54mm,15u,G,DIP-3 | MOLEX INCORPORATED | 87891-0304 | G | PWA BOM | In New BOM |
|  |  |  | 34065R700-GRT-G | CONN,Pin Header,1X3,V/T,Bla,2.54mm,15u,G,DIP-3 | PINREX TECHNOLOGY CORP. | 21K-81-03HB01 | G | PWA BOM | In New BOM |
|  |  |  | 34065RR00-245-G | CONN,Pin Header,1X3,V/T,Bla,2.54mm,15u,G,DIP-3 | AMPHENOL SHANGHAI CORP. | G800305005EU | G | PWA BOM | In New BOM |
|  | J_PS_ON1 | 1 | 340600S00-600-G | CONN,Pin Header,1X3,V/T,Bla,2.54mm,15u,G,DIP-3 | FOXCONN TECHNOLOGY CO.,LTD. | HB1103V |  | PWA BOM | In Old BOM |
|  |  |  | 34060WK00-317-G | CONN.Pin Header,1X3,V/T,Bla,2.54mm,15u,G,DIP-3 | MOLEX | 87891-0304 | G | PWA BOM | In Old BOM |
|  |  |  | 34065R700-GRT-G | CONN,Pin Header,1X3,V/T,Bla,2.54mm,15u,G,DIP-3 | PINREX | 21K-81-03HB01 | G | PWA BOM | In Old BOM |
|  |  |  | 34065RR00-245-G | CONN,Pin Header,1X3,V/T,Bla,2.54mm,15u,G,DIP-3 | AMPHENOL | G800305005EU | G | PWA BOM | In Old BOM |
| 79 | PCB | 1 | 0101F1100-000-G | PCB,Zaius-FPDB DVT-X01,OSP,Blu,6L,18.2623*7.025,G | GOLD CIRCUIT ELECTRONICS LTD. | 0101F1100-000-G | G | PWA BOM | In New BOM |
|  |  |  | 0101F1100-000-G | PCB,Zaius-FPDB DVT-X01,OSP,Blu,6L,18.2623*7.025,G | ZHUHAI FOUNDER PRINTED CIRCUIT BOARD（HK） DEVELOPMENT LIMITED | 0101F1100-000-G |  | PWA BOM | In New BOM |
|  | PCB | 1 | 0101F1100-000-G | PCB,Zaius-FPDB DVT-X01,OSP,Blu,6L,18.2623*7.025,G | GOLD CIRCUIT ELECTRONICS LTD. | 0101F1100-000-G |  | PWA BOM | In Old BOM |
|  |  |  | 0101F1100-000-G | PCB,Zaius-FPDB DVT-X01,OSP,Blu,6L,18.2623*7.025,G | ZHUHAI FOUNDER PRINTED CIRCUIT BOARD（HK） DEVELOPMENT LIMITED | 0101F1100-000-G |  | PWA BOM | In Old BOM |
| 80 | D1,D2,D3,D4,D5,PHAD6,D6,D7,D8,D9,D10,D11,D12 | 13 | 520100200-237-G | DIODE,Switching,1N4148W-7-F,100V,0.15A,G,SOD123-2,SMD | DIODES INCORPORATION | 1N4148W-7-F | N | PWA BOM | In New BOM |
|  | D1,D2,D3,D4,D5,PHAD6,D6,D7,D8,D9,D10,D11,D12 | 13 | 520100200-237-G | DIODE,Switching,1N4148W-7-F,100V,0.15A,G,SOD123-2,SMD | DIODES INEORPORATION | 1N4148W-7-F | N | PWA BOM | In Old BOM |
| 81 | D34 | 1 | 520401Y00-237-G | DIODE,Zener,BZT52C3V6-7-F,3.6V,5mA,G,SOD123-2,SMD | DIODES INCORPORATION | BZT52C3V6-7-F | N | PWA BOM | In New BOM |
|  |  |  | 520407600-223-G | Diode,ZENER,MMSZ3V6T1G,3.6V,5mA,SOD-123,2P,G | ON SEMICONDUCTOR CORP | MMSZ3V6T1G | G | PWA BOM | In New BOM |
|  | D34 | 1 | 520401Y00-237-G | DIODE,Zener,BZT52C3V6-7-F,3.6V,5mA,G,SOD123-2,SMD | DIODES INEORPORATION | BZT52C3V6-7-F | N | PWA BOM | In Old BOM |
|  |  |  | 520407600-223-G | Diode,ZENER,MMSZ3V6T1G,3.6V,5mA,SOD-123,2P,G | ON SEMICONDUCTOR CORP | MMSZ3V6T1G | G | PWA BOM | In Old BOM |
| 82 | J4,J5,J6,J7,J8,J9 | 6 | 340699J00-317-G | CONN,Header,WTB,1X8,V/T,Bla,2.54mm,G,DIP-8 | MOLEX INCORPORATED | 22-23-2081 |  | PWA BOM | In New BOM |
|  | J4,J5,J6,J7,J8,J9 | 6 | 22-23-2081 | CONN,Header,WTB,1X8,V/T,Bla,2.54mm,G,DIP-8 | MOLEX INCORPORATED | 22-23-2081 |  | PWA BOM | In Old BOM |
| 83 | PEUR1 | 1 | 610119C00-017-G | RES,130KOhm,+/-1%,1/16W,G,SMD0402 | KOA SPEER ELECTRONICS, INC. | RK73H1ETTP1303F | N | PWA BOM | In New BOM |
|  | PEUR1 | 1 | 61010G500-017-G | RES,10KOhm,+/-1%,1/16W,G,SMD0402 | KOA SPEER ELECTRONICS, INC. | RK73H1ETTP1002F | N | PWA BOM | In Old BOM |
|  |  |  | 61010G500-012-G | RES,10KOhm,+/-1%,1/16W,G,SMD0402 | WALSIN | WR04X1002FTL | G | PWA BOM | In Old BOM |
|  |  |  | 61010G500-011-G | RES,10KOhm,+/-1%,1/16W,G,SMD0402 | YAGEO | RC0402FR-0710KL | G | PWA BOM | In Old BOM |
|  |  |  | 61010G500-044-G | RES,10KOhm,+/-1%,1/16W,G,SMD0402 | TA-I | RM04FTN1002 | G | PWA BOM | In Old BOM |
|  |  |  | 61010G500-029-G | RES,10KOhm,+/-1%,1/16W,G,SMD0402 | VISHAY | CRCW040210K0FKED | G | PWA BOM | In Old BOM |
|  |  |  | 61010G500-024-G | RES,10KOhm,+/-1%,1/16W,G,SMD0402 | PANASONIC | ERJ2RKF1002X | G | PWA BOM | In Old BOM |
| 84 | PHAQ8 | 1 | 510100W00-237-G | TRANS N,MMBT3904-7-F,40V,0.2A,G,SOT23-3,SMD | DIODES INCORPORATION | MMBT3904-7-F | N | PWA BOM | In New BOM |
|  |  |  | 510101700-185-G | TRANS N,MMBT3904,40V,0.2A,G,SOT23-3,SMD | FAIRCHILD SEMICONDUCTOR CORP | MMBT3904 | G | PWA BOM | In New BOM |
|  |  |  | 510100800-223-G | TRANS N,MMBT3904LT1G,40V,0.2A,G,SOT23-3,SMD | ON SEMICONDUCTOR CORP | MMBT3904LT1G | G | PWA BOM | In New BOM |
|  |  |  | 510100500-031-G | TRANS N,PMBT3904,40V,0.2A,G,SOT23-3,SMD | NXP SEMICONDUCTORS | PMBT3904 | G | PWA BOM | In New BOM |
|  | PHAQ8 | 1 | 510100W00-237-G | TRANS N,MMBT3904-7-F,40V,0.2A,G,SOT23-3,SMD | DIODES INEORPORATION | MMBT3904-7-F | N | PWA BOM | In Old BOM |
|  |  |  | 510101700-185-G | TRANS N,MMBT3904,40V,0.2A,G,SOT23-3,SMD | FAIRCHILD SEMICONDUCTOR CORP | MMBT3904 | G | PWA BOM | In Old BOM |
|  |  |  | 510100800-223-G | TRANS N,MMBT3904LT1G,40V,0.2A,G,SOT23-3,SMD | ON SEMICONDUCTOR CORP | MMBT3904LT1G | G | PWA BOM | In Old BOM |
|  |  |  | 510100500-031-G | TRANS N,PMBT3904,40V,0.2A,G,SOT23-3,SMD | NXP SEMICONDUCTORS | PMBT3904 | G | PWA BOM | In Old BOM |
| 85 | PSUR1 | 1 | 61011NY00-017-G | RES,88.7KOhm,+/-1%,1/16W,G,SMD0402 | KOA SPEER ELECTRONICS, INC. | RK73H1ETTP8872F | N | PWA BOM | In New BOM |
|  | PSUR1 | 1 | 610115R00-017-G | RES,15KOhm,+/-1%,1/16W,G,SMD0402 | KOA SPEER ELECTRONICS, INC. | RK73H1ETTP1502F | N | PWA BOM | In Old BOM |
|  |  |  | 610115R00-012-G | RES,15KOhm,+/-1%,1/16W,G,SMD0402 | WALSIN | WR04X1502FTL | G | PWA BOM | In Old BOM |
|  |  |  | 610115R00-011-G | RES,15KOhm,+/-1%,1/16W,G,SMD0402 | YAGEO | RC0402FR-0715KL | G | PWA BOM | In Old BOM |
|  |  |  | 610115R00-044-G | RES,15KOhm,+/-1%,1/16W,G,SMD0402 | TA-I | RM04FTN1502 | G | PWA BOM | In Old BOM |
|  |  |  | 610115R00-024-G | RES,15KOhm,+/-1%,1/16W,G,SMD0402 | PANASONIC | ERJ2RKF1502X | G | PWA BOM | In Old BOM |
|  |  |  | 610115R00-029-G | RES,15KOhm,+/-1%,1/16W,G,SMD0402 | VISHAY | CRCW040215K0FKED | G | PWA BOM | In Old BOM |
| ##### Change Revision |  |  |  |  |  |  |  |  |  |
| Sheet | REV OF BOM | CUSTOMER | CUSTOMER P/N | PWA PN | PWA DESCRIPTION | PWA REV | DATE | Remark |  |
| PWA BOM | X02 | Customer |  |  |  | X01 | 5/15/17 | In New BOM |  |
| PWA BOM |  | Customer |  |  |  |  |  | In Old BOM |  |
| OOOOOOOOOOOOOOOOOOOOOOOOOOOOOOOOOOOOOOOOOOOOOOOOOOOOOOOOOOOOOOOOOOOOOOOOOOOOOOOOOOOOOOOOOO | OOOOOOOOOOOOOOOOOOOOOOOOOOOOOOOOOOOOOOOOOOOOOOOOOOOOOOOOOOOOOOOOOOOOOOOOOOOOOOOOOOOOOOOOOO | OOOOOOOOOOOOOOOOOOOOOOOOOOOOOOOOOOOOOOOOOOOOOOOOOOOOOOOOOOOOOOOOOOOOOOOOOOOOOOOOOOOOOOOOOO | OOOOOOOOOOOOOOOOOOOOOOOOOOOOOOOOOOOOOOOOOOOOOOOOOOOOOOOOOOOOOOOOOOOOOOOOOOOOOOOOOOOOOOOOOO | OOOOOOOOOOOOOOOOOOOOOOOOOOOOOOOOOOOOOOOOOOOOOOOOOOOOOOOOOOOOOOOOOOOOOOOOOOOOOOOOOOOOOOOOOO | OOOOOOOOOOOOOOOOOOOOOOOOOOOOOOOOOOOOOOOOOOOOOOOOOOOOOOOOOOOOOOOOOOOOOOOOOOOOOOOOOOOOOOOOOO | OOOOOOOOOOOOOOOOOOOOOOOOOOOOOOOOOOOOOOOOOOOOOOOOOOOOOOOOOOOOOOOOOOOOOOOOOOOOOOOOOOOOOOOOOO | OOOOOOOOOOOOOOOOOOOOOOOOOOOOOOOOOOOOOOOOOOOOOOOOOOOOOOOOOOOOOOOOOOOOOOOOOOOOOOOOOOOOOOOOOO | OOOOOOOOOOOOOOOOOOOOOOOOOOOOOOOOOOOOOOOOOOOOOOOOOOOOOOOOOOOOOOOOOOOOOOOOOOOOOOOOOOOOOOOOOO | OOOOOOOOOOOOOOOOOOOOOOOOOOOOOOOOOOOOOOOOOOOOOOOOOOOOOOOOOOOOOOOOOOOOOOOOOOOOOOOOOOOOOOOOOO |
| Second Source Change |  |  |  |  |  |  |  |  |  |
| Item | Location | Change Type | Foxconn P/N | Part Description | Manufacturer Full Name | Manufacturer P/N | RoHS | Sheet |  |
| 1 | FS4,FS5,FS6,FS7,FS8,FS9 |  | 730103M00-086-G | Fuse,Fast acting,32V,5A,G,SMD0603 | LITTELFUSE FAR EAST PTE LTD | 0438005.WR | Y | PWA BOM |  |
|  |  | NO | 730103M00-088-G | Fuse,Fast acting,32V,5A,SMD0603,G | COOPER BUSSMANN, INC. | CC06H5A-TR | G | PWA BOM |  |
|  |  | Delete | 730100H00-085-G | Fuse,Very fast acting,32V,5A,G,SMD0603 | BEL FUSE INC | C2Q 5TR | G | PWA BOM |  |
| 2 | PHAQ4 |  | 51020A000-031-G | TRANS P,PBHV9115T,150V,1A,G,SOT23-3,SMD | NXP SEMICONDUCTORS | PBHV9115T |  | PWA BOM |  |
|  |  | NO | 51020AF00-280-G | Trans PNP,MMBT5401,-150V,-500mA,SOT-23,3P,G | FAIRCHILD SEMICONDUCTOR CORP | MMBT5401 | G | PWA BOM |  |
|  |  | ADD | MMBT5401 | TRANS,150V,1A,G,SOT23-3,SMD | DIODES INCORPORATION | MMBT5401 |  | PWA BOM |  |
| 3 | PHAQ5,PHAQ9 |  | 51032D100-237-G | MOS N,DMN10H220L-7,100V,1.6A,220m@10V,G,SOT-23-3,SMD | DIODES INCORPORATION | DMN10H220L-7 |  | PWA BOM |  |
|  |  | ADD | FQT7N10LTF | MOS N,FQT7N10LTF | FAIRCHILD SEMICONDUCTOR CORP | FQT7N10LTF | G | PWA BOM |  |
|  |  | Delete | FQT7N10L | MOS N,FQT7N10L | Fairchild | FQT7N10L | G | PWA BOM |  |
| 4 | QN4 |  | 510503B00-223-G | MOS N/N,NTZD3154NT1G,20V,0.54A,550m24.5V,G,SOT563-6,SMD | ON SEMICONDUCTOR CORP | NTZD3154NT1G | N | PWA BOM |  |
|  |  | NO | Si1034CX-T1-GE3 | MOS N/N,Si1034CX-T1-GE3 | VISHAY ENTER TECHNO LOGY.INC | Si1034CX-T1-GE3 | G | PWA BOM |  |
|  |  | NO | SSM6N36FE | MOS N/N,SSM6N36FE | TOSHIBA ELECTRONICS ASIA LTD | SSM6N36FE | G | PWA BOM |  |
|  |  | Delete | 51050AK00-030-G | MOS N/N,EM6K6T2R,20V,0.3A,1ohm@4V,G,EMT-6,SMD | ROHM CORPORATION | EM6K6T2R | G | PWA BOM |  |
| 5 | U109 |  | 310307T00-031-G | IC,Switch,74CBTLV1G125GV,2.3~3.6V,G,SOT753-5,SMD | NXP SEMICONDUCTORS | 74CBTLV1G125GV |  | PWA BOM |  |
|  |  | ADD | 310300D00-183-G | IC,Switch,SN74CBTLV1G125DBVR,2.3~3.6V,G,SOT23-5,SMD | TEXAS INSTRUMENTS | SN74CBTLV1G125DBVR | G | PWA BOM |  |
|  |  | Delete | SN74CBTLV1G125DBVR | IC,Switch,SN74CBTLV1G125DBVR,2.3~3.6V,G,SOT23-5,SMD | TI | SN74CBTLV1G125DBVR | G | PWA BOM |  |
| 6 | J_PS_ON_SW(2-3)1 |  | 340612R00-309-G | CONN,Jumper,Bla,2.54mm,G,DIP-2 | SAMTEC INC. | SNT-100-BK-G |  | PWA BOM |  |
|  |  | NO | 34065L900-GRT-G | CONN,jumper,Bla,2.54mm,30u,G,DIP-2 | PINREX TECHNOLOGY CORP. | 201-71-01DB00 | G | PWA BOM |  |
|  |  | NO | 34066N500-600-G | Header&Socket Connector,SJ0520F-A0,Jumper,2,DIP,PBT,2.54mm,3u",Black,G | FOXCONN TECHNOLOGY CO.,LTD. | SJ0520F-A0 | G | PWA BOM |  |
|  |  | Delete | 34069RA00-637-G | Header&Socket Connector,1200210020,Jumper,2,DIP,PBT,2.54mm,3u",Black,G | LONG SHOUNG CO.,LTD. | 1200210020 | G | PWA BOM |  |
| OOOOOOOOOOOOOOOOOOOOOOOOOOOOOOOOOOOOOOOOOOOOOOOOOOOOOOOOOOOOOOOOOOOOOOOOOOOOOOOOOOOOOOOOOO | OOOOOOOOOOOOOOOOOOOOOOOOOOOOOOOOOOOOOOOOOOOOOOOOOOOOOOOOOOOOOOOOOOOOOOOOOOOOOOOOOOOOOOOOOO | OOOOOOOOOOOOOOOOOOOOOOOOOOOOOOOOOOOOOOOOOOOOOOOOOOOOOOOOOOOOOOOOOOOOOOOOOOOOOOOOOOOOOOOOOO | OOOOOOOOOOOOOOOOOOOOOOOOOOOOOOOOOOOOOOOOOOOOOOOOOOOOOOOOOOOOOOOOOOOOOOOOOOOOOOOOOOOOOOOOOO | OOOOOOOOOOOOOOOOOOOOOOOOOOOOOOOOOOOOOOOOOOOOOOOOOOOOOOOOOOOOOOOOOOOOOOOOOOOOOOOOOOOOOOOOOO | OOOOOOOOOOOOOOOOOOOOOOOOOOOOOOOOOOOOOOOOOOOOOOOOOOOOOOOOOOOOOOOOOOOOOOOOOOOOOOOOOOOOOOOOOO | OOOOOOOOOOOOOOOOOOOOOOOOOOOOOOOOOOOOOOOOOOOOOOOOOOOOOOOOOOOOOOOOOOOOOOOOOOOOOOOOOOOOOOOOOO | OOOOOOOOOOOOOOOOOOOOOOOOOOOOOOOOOOOOOOOOOOOOOOOOOOOOOOOOOOOOOOOOOOOOOOOOOOOOOOOOOOOOOOOOOO | OOOOOOOOOOOOOOOOOOOOOOOOOOOOOOOOOOOOOOOOOOOOOOOOOOOOOOOOOOOOOOOOOOOOOOOOOOOOOOOOOOOOOOOOOO | OOOOOOOOOOOOOOOOOOOOOOOOOOOOOOOOOOOOOOOOOOOOOOOOOOOOOOOOOOOOOOOOOOOOOOOOOOOOOOOOOOOOOOOOOO |
| Master Materials Change |  |  |  |  |  |  |  |  |  |
| Item | Foxconn P/N | Orig._Usage | New_Usage | Part Description | Manufacturer Full Name | Manufacturer P/N | RoHS | Location | Sheet |
| 1 | 340699J00-317-G | 0 | 6 | CONN,Header,WTB,1X8,V/T,Bla,2.54mm,G,DIP-8 | MOLEX INCORPORATED | 22-23-2081 |  | (+)J4,J5,J6,J7,J8,J9 | PWA BOM |
| 2 | 610119C00-017-G | 0 | 1 | RES,130KOhm,+/-1%,1/16W,G,SMD0402 | KOA SPEER ELECTRONICS, INC. | RK73H1ETTP1303F | N | (+)PEUR1 | PWA BOM |
| 3 | 610116G00-017-G | 0 | 3 | RES,150KOhm,+/-1%,1/16W,G,SMD0402 | KOA SPEER ELECTRONICS, INC. | RK73H1ETTP1503F | N | (+)PSUR2,PEUR2,PEUR7 | PWA BOM |
| 4 | 610118S00-017-G | 0 | 2 | RES,54.9KOhm,+/-1%,1/16W,G,SMD0402 | KOA SPEER ELECTRONICS, INC. | RK73H1ETTP5492F | N | (+)PSUR4,PEUR6 | PWA BOM |
| 5 | 61010G500-017-G | 18 | 17 | RES,10KOhm,+/-1%,1/16W,G,SMD0402 | KOA SPEER ELECTRONICS, INC. | RK73H1ETTP1002F | N | (-)PEUR1 | PWA BOM |
|  | 61010G500-012-G |  |  | RES,10KOhm,+/-1%,1/16W,G,SMD0402 | WALSIN TECHNOLOGY CORPORATION | WR04X1002FTL |  |  | PWA BOM |
|  | 61010G500-011-G |  |  | RES,10KOhm,+/-1%,1/16W,G,SMD0402 | YAGEO CORPORATION COMPONENT | RC0402FR-0710KL |  |  | PWA BOM |
|  | 61010G500-044-G |  |  | RES,10KOhm,+/-1%,1/16W,G,SMD0402 | TA-I TECHNOLOGY CO., LTD. | RM04FTN1002 |  |  | PWA BOM |
|  | 61010G500-029-G |  |  | RES,10KOhm,+/-1%,1/16W,G,SMD0402 | VISHAY ENTER TECHNO LOGY.INC | CRCW040210K0FKED |  |  | PWA BOM |
|  | 61010G500-024-G |  |  | RES,10KOhm,+/-1%,1/16W,G,SMD0402 | PANASONIC INDUSTRIAL CO.,LTD. | ERJ2RKF1002X |  |  | PWA BOM |
| 6 | 61011NY00-017-G | 0 | 1 | RES,88.7KOhm,+/-1%,1/16W,G,SMD0402 | KOA SPEER ELECTRONICS, INC. | RK73H1ETTP8872F | N | (+)PSUR1 | PWA BOM |
| 7 | 61011N000-017-G | 0 | 1 | RES,68KOhm,+/-1%,1/16W,G,SMD0402 | KOA SPEER ELECTRONICS, INC. | RK73H1ETTP6802F | N | (+)PSUR5 | PWA BOM |
| 8 | 34080F500-653-G | 0 | 2 | CONN,Switch,slide,25mA,24V,G,SMD-8 | DIPTRONICS MANUFACTURING INC. | DHN-04F-T-V-T/R |  | (+)PSUSW1,PEUSW1 | PWA BOM |
| 9 | 22-23-2081 | 6 | 0 | CONN,Header,WTB,1X8,V/T,Bla,2.54mm,G,DIP-8 | MOLEX INCORPORATED | 22-23-2081 |  | (-)J4,J5,J6,J7,J8,J9 | PWA BOM |
| 10 | 610115R00-017-G | 1 | 0 | RES,15KOhm,+/-1%,1/16W,G,SMD0402 | KOA SPEER ELECTRONICS, INC. | RK73H1ETTP1502F | N | (-)PSUR1 | PWA BOM |
|  | 610115R00-012-G |  |  | RES,15KOhm,+/-1%,1/16W,G,SMD0402 | WALSIN | WR04X1502FTL |  |  | PWA BOM |
|  | 610115R00-011-G |  |  | RES,15KOhm,+/-1%,1/16W,G,SMD0402 | YAGEO | RC0402FR-0715KL |  |  | PWA BOM |
|  | 610115R00-044-G |  |  | RES,15KOhm,+/-1%,1/16W,G,SMD0402 | TA-I | RM04FTN1502 |  |  | PWA BOM |
|  | 610115R00-024-G |  |  | RES,15KOhm,+/-1%,1/16W,G,SMD0402 | PANASONIC | ERJ2RKF1502X |  |  | PWA BOM |
|  | 610115R00-029-G |  |  | RES,15KOhm,+/-1%,1/16W,G,SMD0402 | VISHAY | CRCW040215K0FKED |  |  | PWA BOM |
| OOOOOOOOOOOOOOOOOOOOOOOOOOOOOOOOOOOOOOOOOOOOOOOOOOOOOOOOOOOOOOOOOOOOOOOOOOOOOOOOOOOOOOOOOO | OOOOOOOOOOOOOOOOOOOOOOOOOOOOOOOOOOOOOOOOOOOOOOOOOOOOOOOOOOOOOOOOOOOOOOOOOOOOOOOOOOOOOOOOOO | OOOOOOOOOOOOOOOOOOOOOOOOOOOOOOOOOOOOOOOOOOOOOOOOOOOOOOOOOOOOOOOOOOOOOOOOOOOOOOOOOOOOOOOOOO | OOOOOOOOOOOOOOOOOOOOOOOOOOOOOOOOOOOOOOOOOOOOOOOOOOOOOOOOOOOOOOOOOOOOOOOOOOOOOOOOOOOOOOOOOO | OOOOOOOOOOOOOOOOOOOOOOOOOOOOOOOOOOOOOOOOOOOOOOOOOOOOOOOOOOOOOOOOOOOOOOOOOOOOOOOOOOOOOOOOOO | OOOOOOOOOOOOOOOOOOOOOOOOOOOOOOOOOOOOOOOOOOOOOOOOOOOOOOOOOOOOOOOOOOOOOOOOOOOOOOOOOOOOOOOOOO | OOOOOOOOOOOOOOOOOOOOOOOOOOOOOOOOOOOOOOOOOOOOOOOOOOOOOOOOOOOOOOOOOOOOOOOOOOOOOOOOOOOOOOOOOO | OOOOOOOOOOOOOOOOOOOOOOOOOOOOOOOOOOOOOOOOOOOOOOOOOOOOOOOOOOOOOOOOOOOOOOOOOOOOOOOOOOOOOOOOOO | OOOOOOOOOOOOOOOOOOOOOOOOOOOOOOOOOOOOOOOOOOOOOOOOOOOOOOOOOOOOOOOOOOOOOOOOOOOOOOOOOOOOOOOOOO | OOOOOOOOOOOOOOOOOOOOOOOOOOOOOOOOOOOOOOOOOOOOOOOOOOOOOOOOOOOOOOOOOOOOOOOOOOOOOOOOOOOOOOOOOO |
| TLA Parts Change |  |  |  |  |  |  |  |  |  |
| Item | Foxconn P/N | Qty | Part Description | Manufacturer Full Name | Manufacturer P/N | RoHS | Location | Remark | BOM |
| 1 | 7J-004-938 | 2 | L6 LABEL ( 12.7*11.1mm) | FOXCONN / EPD1 | 7J-004-938 | G |  | ID label for two boards. FPDB AA P/N: 1A42G4V00-600-G Post card AA P/N: 1A42GQG00-600-G | In Old BOM |
| BOM Change List Date:Thu May 25 19:17:07 GMT+08:00 2017 |  |  |  |  |  |  |  |  |  |
| New BOM file : C:\<user>\BARRELEYE_G2-FPDB_POST-DVT-X01-BOM-X02-20170525.xls |  |  |  |  |  |  |  |  |  |
| Old BOM file : C:\<user>\BARRELEYE_G2-FPDB_POST-DVT-X01-BOM-X02-20170516.xls |  |  |  |  |  |  |  |  |  |
| ##### Add Parts |  |  |  |  |  |  |  |  |  |
| Item | Location | Qty | Foxconn P/N | Part Description | Manufacturer Full Name | Manufacturer P/N | RoHS | Sheet |  |
| ##### Remove Parts |  |  |  |  |  |  |  |  |  |
| Item | Location | Qty | Foxconn P/N | Part Description | Manufacturer Full Name | Manufacturer P/N | RoHS | Sheet |  |
| ##### Change Parts |  |  |  |  |  |  |  |  |  |
| Item | Location | Qty | Foxconn P/N | Part Description | Manufacturer Full Name | Manufacturer P/N | RoHS | Sheet | Remark |
| 1 | D1,D2,D3,D4,D5,PHAD6,D6,D7,D8,D9,D10,D11,D12 | 13 | 520100200-237-G | DIODE,Switching,1N4148W-7-F,100V,0.15A,G,SOD123-2,SMD | DIODES INCORPORATION | 1N4148W-7-F | G | PWA BOM | In New BOM |
|  |  |  | 520102P00-031-G | DIODE,Switching,BAS16H,100V,0.5A,G,SOD123F-2,SMD | NXP SEMICONDUCTORS | BAS16H | G | PWA BOM | In New BOM |
|  | D1,D2,D3,D4,D5,PHAD6,D6,D7,D8,D9,D10,D11,D12 | 13 | 520100200-237-G | DIODE,Switching,1N4148W-7-F,100V,0.15A,G,SOD123-2,SMD | DIODES INCORPORATION | 1N4148W-7-F | G | PWA BOM | In Old BOM |
| 2 | PHAQ4 | 1 | 51020A000-031-G | TRANS P,PBHV9115T,150V,1A,G,SOT23-3,SMD | NXP SEMICONDUCTORS | PBHV9115T | G | PWA BOM | In New BOM |
|  |  |  | MMBT5401 | TRANS,150V,1A,G,SOT23-3,SMD | FAIRCHILD SEMICONDUCTOR CORP | MMBT5401 | G | PWA BOM | In New BOM |
|  |  |  | MMBT5401_1 | TRANS,150V,1A,G,SOT23-3,SMD | DIODES INCORPORATION | MMBT5401_1 | G | PWA BOM | In New BOM |
|  | PHAQ4 | 1 | 51020A000-031-G | TRANS P,PBHV9115T,150V,1A,G,SOT23-3,SMD | NXP SEMICONDUCTORS | PBHV9115T | G | PWA BOM | In Old BOM |
|  |  |  | 51020AF00-280-G | Trans PNP,MMBT5401,-150V,-500mA,SOT-23,3P,G | FAIRCHILD SEMICONDUCTOR CORP | MMBT5401 | G | PWA BOM | In Old BOM |
|  |  |  | MMBT5401 | TRANS,150V,1A,G,SOT23-3,SMD | DIODES INCORPORATION | MMBT5401 |  | PWA BOM | In Old BOM |
| 3 | Y1,Y2 | 2 | 71020KL00-100-G | OSC,33MHz,+/-50ppm,3.3V,15pF,G,SMD | TXC CORPORATION | 7X33000013 | G | PWA BOM | In New BOM |
|  | Y1,Y2 | 2 | 71020KL00-100-G | OSC,33MHz,+/-50ppm,3.3V,15pF,G,SMD | TXC CORPORATION | 7X33000013 | G | PWA BOM | In Old BOM |
|  |  |  | 710211700-16G-G | OSC,33MHz,+/-25ppm,3.3V,15pF,,-40_x0003_~85_x0003_,SMD,G | SiTime Corporation | SIT1602AI-22-33E-33.000000D | G | PWA BOM | In Old BOM |
| 4 | PSUQ1 | 1 | 510301N00-223-G | MOS N,2N7002LT1G,60V,0.115A,7.5ohm@5V,G,SOT23-3,SMD | ON SEMICONDUCTOR CORP | 2N7002LT1G | G | PWA BOM | In New BOM |
|  |  |  | 51030CQ00-185-G | MOS N,2N7002,60V,115mA,7.5ohm@5V,G,SOT23-3,SMD | FAIRCHILD SEMICONDUCTOR CORP | 2N7002 | G | PWA BOM | In New BOM |
|  | PSUQ1 | 1 | 51030CQ00-185-G | MOS N,2N7002,60V,115mA,7.5ohm@5V,G,SOT23-3,SMD | FAIRCHILD SEMICONDUCTOR CORP | 2N7002 | G | PWA BOM | In Old BOM |
|  |  |  | 510301N00-223-G | MOS N,2N7002LT1G,60V,0.115A,7.5ohm@5V,G,SOT23-3,SMD | ON SEMICONDUCTOR CORP | 2N7002LT1G | G | PWA BOM | In Old BOM |
| ##### Change Revision |  |  |  |  |  |  |  |  |  |
| Sheet | REV OF BOM | CUSTOMER | CUSTOMER P/N | PWA PN | PWA DESCRIPTION | PWA REV | DATE | Remark |  |
| OOOOOOOOOOOOOOOOOOOOOOOOOOOOOOOOOOOOOOOOOOOOOOOOOOOOOOOOOOOOOOOOOOOOOOOOOOOOOOOOOOOOOOOOOO | OOOOOOOOOOOOOOOOOOOOOOOOOOOOOOOOOOOOOOOOOOOOOOOOOOOOOOOOOOOOOOOOOOOOOOOOOOOOOOOOOOOOOOOOOO | OOOOOOOOOOOOOOOOOOOOOOOOOOOOOOOOOOOOOOOOOOOOOOOOOOOOOOOOOOOOOOOOOOOOOOOOOOOOOOOOOOOOOOOOOO | OOOOOOOOOOOOOOOOOOOOOOOOOOOOOOOOOOOOOOOOOOOOOOOOOOOOOOOOOOOOOOOOOOOOOOOOOOOOOOOOOOOOOOOOOO | OOOOOOOOOOOOOOOOOOOOOOOOOOOOOOOOOOOOOOOOOOOOOOOOOOOOOOOOOOOOOOOOOOOOOOOOOOOOOOOOOOOOOOOOOO | OOOOOOOOOOOOOOOOOOOOOOOOOOOOOOOOOOOOOOOOOOOOOOOOOOOOOOOOOOOOOOOOOOOOOOOOOOOOOOOOOOOOOOOOOO | OOOOOOOOOOOOOOOOOOOOOOOOOOOOOOOOOOOOOOOOOOOOOOOOOOOOOOOOOOOOOOOOOOOOOOOOOOOOOOOOOOOOOOOOOO | OOOOOOOOOOOOOOOOOOOOOOOOOOOOOOOOOOOOOOOOOOOOOOOOOOOOOOOOOOOOOOOOOOOOOOOOOOOOOOOOOOOOOOOOOO | OOOOOOOOOOOOOOOOOOOOOOOOOOOOOOOOOOOOOOOOOOOOOOOOOOOOOOOOOOOOOOOOOOOOOOOOOOOOOOOOOOOOOOOOOO | OOOOOOOOOOOOOOOOOOOOOOOOOOOOOOOOOOOOOOOOOOOOOOOOOOOOOOOOOOOOOOOOOOOOOOOOOOOOOOOOOOOOOOOOOO |
| Second Source Change |  |  |  |  |  |  |  |  |  |
| Item | Location | Change Type | Foxconn P/N | Part Description | Manufacturer Full Name | Manufacturer P/N | RoHS | Sheet |  |
| 1 | D1,D2,D3,D4,D5,PHAD6,D6,D7,D8,D9,D10,D11,D12 |  | 520100200-237-G | DIODE,Switching,1N4148W-7-F,100V,0.15A,G,SOD123-2,SMD | DIODES INCORPORATION | 1N4148W-7-F | G | PWA BOM |  |
|  |  | ADD | 520102P00-031-G | DIODE,Switching,BAS16H,100V,0.5A,G,SOD123F-2,SMD | NXP SEMICONDUCTORS | BAS16H | G | PWA BOM |  |
| 2 | PHAQ4 |  | 51020A000-031-G | TRANS P,PBHV9115T,150V,1A,G,SOT23-3,SMD | NXP SEMICONDUCTORS | PBHV9115T | G | PWA BOM |  |
|  |  | NO | MMBT5401 | TRANS,150V,1A,G,SOT23-3,SMD | FAIRCHILD SEMICONDUCTOR CORP | MMBT5401 | G | PWA BOM |  |
|  |  | ADD | MMBT5401 | TRANS,150V,1A,G,SOT23-3,SMD | DIODES INCORPORATION | MMBT5401 | G | PWA BOM |  |
|  |  | Delete | 51020AF00-280-G | Trans PNP,MMBT5401,-150V,-500mA,SOT-23,3P,G | FAIRCHILD SEMICONDUCTOR CORP | MMBT5401 | G | PWA BOM |  |
| 3 | Y1,Y2 |  | 71020KL00-100-G | OSC,33MHz,+/-50ppm,3.3V,15pF,G,SMD | TXC CORPORATION | 7X33000013 | G | PWA BOM |  |
|  |  | Delete | 710211700-16G-G | OSC,33MHz,+/-25ppm,3.3V,15pF,,-40_x0003_~85_x0003_,SMD,G | SiTime Corporation | SIT1602AI-22-33E-33.000000D | G | PWA BOM |  |
| OOOOOOOOOOOOOOOOOOOOOOOOOOOOOOOOOOOOOOOOOOOOOOOOOOOOOOOOOOOOOOOOOOOOOOOOOOOOOOOOOOOOOOOOOO | OOOOOOOOOOOOOOOOOOOOOOOOOOOOOOOOOOOOOOOOOOOOOOOOOOOOOOOOOOOOOOOOOOOOOOOOOOOOOOOOOOOOOOOOOO | OOOOOOOOOOOOOOOOOOOOOOOOOOOOOOOOOOOOOOOOOOOOOOOOOOOOOOOOOOOOOOOOOOOOOOOOOOOOOOOOOOOOOOOOOO | OOOOOOOOOOOOOOOOOOOOOOOOOOOOOOOOOOOOOOOOOOOOOOOOOOOOOOOOOOOOOOOOOOOOOOOOOOOOOOOOOOOOOOOOOO | OOOOOOOOOOOOOOOOOOOOOOOOOOOOOOOOOOOOOOOOOOOOOOOOOOOOOOOOOOOOOOOOOOOOOOOOOOOOOOOOOOOOOOOOOO | OOOOOOOOOOOOOOOOOOOOOOOOOOOOOOOOOOOOOOOOOOOOOOOOOOOOOOOOOOOOOOOOOOOOOOOOOOOOOOOOOOOOOOOOOO | OOOOOOOOOOOOOOOOOOOOOOOOOOOOOOOOOOOOOOOOOOOOOOOOOOOOOOOOOOOOOOOOOOOOOOOOOOOOOOOOOOOOOOOOOO | OOOOOOOOOOOOOOOOOOOOOOOOOOOOOOOOOOOOOOOOOOOOOOOOOOOOOOOOOOOOOOOOOOOOOOOOOOOOOOOOOOOOOOOOOO | OOOOOOOOOOOOOOOOOOOOOOOOOOOOOOOOOOOOOOOOOOOOOOOOOOOOOOOOOOOOOOOOOOOOOOOOOOOOOOOOOOOOOOOOOO | OOOOOOOOOOOOOOOOOOOOOOOOOOOOOOOOOOOOOOOOOOOOOOOOOOOOOOOOOOOOOOOOOOOOOOOOOOOOOOOOOOOOOOOOOO |
| Master Materials Change |  |  |  |  |  |  |  |  |  |
| Item | Foxconn P/N | Orig._Usage | New_Usage | Part Description | Manufacturer Full Name | Manufacturer P/N | RoHS | Location | Sheet |
| 1 | 510301N00-223-G | 0 | 1 | MOS N,2N7002LT1G,60V,0.115A,7.5ohm@5V,G,SOT23-3,SMD | ON SEMICONDUCTOR CORP | 2N7002LT1G | G | (+)PSUQ1 | PWA BOM |
|  | 51030CQ00-185-G |  |  | MOS N,2N7002,60V,115mA,7.5ohm@5V,G,SOT23-3,SMD | FAIRCHILD SEMICONDUCTOR CORP | 2N7002 |  |  | PWA BOM |
| 2 | 51030CQ00-185-G | 1 | 0 | MOS N,2N7002,60V,115mA,7.5ohm@5V,G,SOT23-3,SMD | FAIRCHILD SEMICONDUCTOR CORP | 2N7002 | G | (-)PSUQ1 | PWA BOM |
|  | 510301N00-223-G |  |  | MOS N,2N7002LT1G,60V,0.115A,7.5ohm@5V,G,SOT23-3,SMD | ON SEMICONDUCTOR CORP | 2N7002LT1G |  |  | PWA BOM |
| OOOOOOOOOOOOOOOOOOOOOOOOOOOOOOOOOOOOOOOOOOOOOOOOOOOOOOOOOOOOOOOOOOOOOOOOOOOOOOOOOOOOOOOOOO | OOOOOOOOOOOOOOOOOOOOOOOOOOOOOOOOOOOOOOOOOOOOOOOOOOOOOOOOOOOOOOOOOOOOOOOOOOOOOOOOOOOOOOOOOO | OOOOOOOOOOOOOOOOOOOOOOOOOOOOOOOOOOOOOOOOOOOOOOOOOOOOOOOOOOOOOOOOOOOOOOOOOOOOOOOOOOOOOOOOOO | OOOOOOOOOOOOOOOOOOOOOOOOOOOOOOOOOOOOOOOOOOOOOOOOOOOOOOOOOOOOOOOOOOOOOOOOOOOOOOOOOOOOOOOOOO | OOOOOOOOOOOOOOOOOOOOOOOOOOOOOOOOOOOOOOOOOOOOOOOOOOOOOOOOOOOOOOOOOOOOOOOOOOOOOOOOOOOOOOOOOO | OOOOOOOOOOOOOOOOOOOOOOOOOOOOOOOOOOOOOOOOOOOOOOOOOOOOOOOOOOOOOOOOOOOOOOOOOOOOOOOOOOOOOOOOOO | OOOOOOOOOOOOOOOOOOOOOOOOOOOOOOOOOOOOOOOOOOOOOOOOOOOOOOOOOOOOOOOOOOOOOOOOOOOOOOOOOOOOOOOOOO | OOOOOOOOOOOOOOOOOOOOOOOOOOOOOOOOOOOOOOOOOOOOOOOOOOOOOOOOOOOOOOOOOOOOOOOOOOOOOOOOOOOOOOOOOO | OOOOOOOOOOOOOOOOOOOOOOOOOOOOOOOOOOOOOOOOOOOOOOOOOOOOOOOOOOOOOOOOOOOOOOOOOOOOOOOOOOOOOOOOOO | OOOOOOOOOOOOOOOOOOOOOOOOOOOOOOOOOOOOOOOOOOOOOOOOOOOOOOOOOOOOOOOOOOOOOOOOOOOOOOOOOOOOOOOOOO |
| TLA Parts Change |  |  |  |  |  |  |  |  |  |
| Item | Foxconn P/N | Qty | Part Description | Manufacturer Full Name | Manufacturer P/N | RoHS | Location | Remark | BOM |
| BOM Change List Date:Thu Jun 01 08:39:39 GMT+08:00 2017 |  |  |  |  |  |  |  |  |  |
| New BOM file : C:\<user>\:\fakepath\BARRELEYE_G2-FPDB_POST-DVT-X01-BOM-X02-20170531.xls |  |  |  |  |  |  |  |  |  |
| Old BOM file : C:\<user>\:\fakepath\BARRELEYE_G2-FPDB_POST-DVT-X01-BOM-X02-20170525.xls |  |  |  |  |  |  |  |  |  |
| ##### Add Parts |  |  |  |  |  |  |  |  |  |
| Item | Location | Qty | Foxconn P/N | Part Description | Manufacturer Full Name | Manufacturer P/N | RoHS | Sheet |  |
| ##### Remove Parts |  |  |  |  |  |  |  |  |  |
| Item | Location | Qty | Foxconn P/N | Part Description | Manufacturer Full Name | Manufacturer P/N | RoHS | Sheet |  |
| ##### Change Parts |  |  |  |  |  |  |  |  |  |
| Item | Location | Qty | Foxconn P/N | Part Description | Manufacturer Full Name | Manufacturer P/N | RoHS | Sheet | Remark |
| 1 | PHAQ4 | 1 | 51020A000-031-G | TRANS P,PBHV9115T,150V,1A,G,SOT23-3,SMD | NXP SEMICONDUCTORS | PBHV9115T | G | PWA BOM | In New BOM |
|  |  |  | MMBT5401 | TRANS,150V,1A,G,SOT23-3,SMD | FAIRCHILD SEMICONDUCTOR CORP | MMBT5401 | G | PWA BOM | In New BOM |
|  |  |  | 510204N00-237-G | Trans PNP,MMBT5401-7-F,-150V,-600mA,SOT-23,3P,G | DIODES INCORPORATION | MMBT5401-7-F | G | PWA BOM | In New BOM |
|  | PHAQ4 | 1 | 51020A000-031-G | TRANS P,PBHV9115T,150V,1A,G,SOT23-3,SMD | NXP SEMICONDUCTORS | PBHV9115T | G | PWA BOM | In Old BOM |
|  |  |  | MMBT5401 | TRANS,150V,1A,G,SOT23-3,SMD | FAIRCHILD SEMICONDUCTOR CORP | MMBT5401 | G | PWA BOM | In Old BOM |
|  |  |  | MMBT5401_1 | TRANS,150V,1A,G,SOT23-3,SMD | DIODES INCORPORATION | MMBT5401_1 | G | PWA BOM | In Old BOM |
| 2 | PHAR1 | 1 | 610601800-32D-G | RES,0.5mOhm,+/-1%,2W,G,SMD1225 | Thin Film Technology Corporation | CPA1225R0M50FW-T5 | G | PWA BOM | In New BOM |
|  | PHAR1 | 1 | 610601800-32D-G | RES,0.5mOhm,+/-1%,2W,G,SMD1225 | Thin Film Technology Corporation | CPA1225R0M50FW-T50 | G | PWA BOM | In Old BOM |
| ##### Change Revision |  |  |  |  |  |  |  |  |  |
| Sheet | REV OF BOM | CUSTOMER | CUSTOMER P/N | PWA PN | PWA DESCRIPTION | PWA REV | DATE | Remark |  |
| OOOOOOOOOOOOOOOOOOOOOOOOOOOOOOOOOOOOOOOOOOOOOOOOOOOOOOOOOOOOOOOOOOOOOOOOOOOOOOOOOOOOOOOOOO | OOOOOOOOOOOOOOOOOOOOOOOOOOOOOOOOOOOOOOOOOOOOOOOOOOOOOOOOOOOOOOOOOOOOOOOOOOOOOOOOOOOOOOOOOO | OOOOOOOOOOOOOOOOOOOOOOOOOOOOOOOOOOOOOOOOOOOOOOOOOOOOOOOOOOOOOOOOOOOOOOOOOOOOOOOOOOOOOOOOOO | OOOOOOOOOOOOOOOOOOOOOOOOOOOOOOOOOOOOOOOOOOOOOOOOOOOOOOOOOOOOOOOOOOOOOOOOOOOOOOOOOOOOOOOOOO | OOOOOOOOOOOOOOOOOOOOOOOOOOOOOOOOOOOOOOOOOOOOOOOOOOOOOOOOOOOOOOOOOOOOOOOOOOOOOOOOOOOOOOOOOO | OOOOOOOOOOOOOOOOOOOOOOOOOOOOOOOOOOOOOOOOOOOOOOOOOOOOOOOOOOOOOOOOOOOOOOOOOOOOOOOOOOOOOOOOOO | OOOOOOOOOOOOOOOOOOOOOOOOOOOOOOOOOOOOOOOOOOOOOOOOOOOOOOOOOOOOOOOOOOOOOOOOOOOOOOOOOOOOOOOOOO | OOOOOOOOOOOOOOOOOOOOOOOOOOOOOOOOOOOOOOOOOOOOOOOOOOOOOOOOOOOOOOOOOOOOOOOOOOOOOOOOOOOOOOOOOO | OOOOOOOOOOOOOOOOOOOOOOOOOOOOOOOOOOOOOOOOOOOOOOOOOOOOOOOOOOOOOOOOOOOOOOOOOOOOOOOOOOOOOOOOOO | OOOOOOOOOOOOOOOOOOOOOOOOOOOOOOOOOOOOOOOOOOOOOOOOOOOOOOOOOOOOOOOOOOOOOOOOOOOOOOOOOOOOOOOOOO |
| Second Source Change |  |  |  |  |  |  |  |  |  |
| Item | Location | Change Type | Foxconn P/N | Part Description | Manufacturer Full Name | Manufacturer P/N | RoHS | Sheet |  |
| 1 | PHAQ4 |  | 51020A000-031-G | TRANS P,PBHV9115T,150V,1A,G,SOT23-3,SMD | NXP SEMICONDUCTORS | PBHV9115T | G | PWA BOM |  |
|  |  | NO | MMBT5401 | TRANS,150V,1A,G,SOT23-3,SMD | FAIRCHILD SEMICONDUCTOR CORP | MMBT5401 | G | PWA BOM |  |
|  |  | ADD | 510204N00-237-G | Trans PNP,MMBT5401-7-F,-150V,-600mA,SOT-23,3P,G | DIODES INCORPORATION | MMBT5401-7-F | G | PWA BOM |  |
|  |  | Delete | MMBT5401 | TRANS,150V,1A,G,SOT23-3,SMD | DIODES INCORPORATION | MMBT5401 | G | PWA BOM |  |
| OOOOOOOOOOOOOOOOOOOOOOOOOOOOOOOOOOOOOOOOOOOOOOOOOOOOOOOOOOOOOOOOOOOOOOOOOOOOOOOOOOOOOOOOOO | OOOOOOOOOOOOOOOOOOOOOOOOOOOOOOOOOOOOOOOOOOOOOOOOOOOOOOOOOOOOOOOOOOOOOOOOOOOOOOOOOOOOOOOOOO | OOOOOOOOOOOOOOOOOOOOOOOOOOOOOOOOOOOOOOOOOOOOOOOOOOOOOOOOOOOOOOOOOOOOOOOOOOOOOOOOOOOOOOOOOO | OOOOOOOOOOOOOOOOOOOOOOOOOOOOOOOOOOOOOOOOOOOOOOOOOOOOOOOOOOOOOOOOOOOOOOOOOOOOOOOOOOOOOOOOOO | OOOOOOOOOOOOOOOOOOOOOOOOOOOOOOOOOOOOOOOOOOOOOOOOOOOOOOOOOOOOOOOOOOOOOOOOOOOOOOOOOOOOOOOOOO | OOOOOOOOOOOOOOOOOOOOOOOOOOOOOOOOOOOOOOOOOOOOOOOOOOOOOOOOOOOOOOOOOOOOOOOOOOOOOOOOOOOOOOOOOO | OOOOOOOOOOOOOOOOOOOOOOOOOOOOOOOOOOOOOOOOOOOOOOOOOOOOOOOOOOOOOOOOOOOOOOOOOOOOOOOOOOOOOOOOOO | OOOOOOOOOOOOOOOOOOOOOOOOOOOOOOOOOOOOOOOOOOOOOOOOOOOOOOOOOOOOOOOOOOOOOOOOOOOOOOOOOOOOOOOOOO | OOOOOOOOOOOOOOOOOOOOOOOOOOOOOOOOOOOOOOOOOOOOOOOOOOOOOOOOOOOOOOOOOOOOOOOOOOOOOOOOOOOOOOOOOO | OOOOOOOOOOOOOOOOOOOOOOOOOOOOOOOOOOOOOOOOOOOOOOOOOOOOOOOOOOOOOOOOOOOOOOOOOOOOOOOOOOOOOOOOOO |
| Master Materials Change |  |  |  |  |  |  |  |  |  |
| Item | Foxconn P/N | Orig._Usage | New_Usage | Part Description | Manufacturer Full Name | Manufacturer P/N | RoHS | Location | Sheet |
| OOOOOOOOOOOOOOOOOOOOOOOOOOOOOOOOOOOOOOOOOOOOOOOOOOOOOOOOOOOOOOOOOOOOOOOOOOOOOOOOOOOOOOOOOO | OOOOOOOOOOOOOOOOOOOOOOOOOOOOOOOOOOOOOOOOOOOOOOOOOOOOOOOOOOOOOOOOOOOOOOOOOOOOOOOOOOOOOOOOOO | OOOOOOOOOOOOOOOOOOOOOOOOOOOOOOOOOOOOOOOOOOOOOOOOOOOOOOOOOOOOOOOOOOOOOOOOOOOOOOOOOOOOOOOOOO | OOOOOOOOOOOOOOOOOOOOOOOOOOOOOOOOOOOOOOOOOOOOOOOOOOOOOOOOOOOOOOOOOOOOOOOOOOOOOOOOOOOOOOOOOO | OOOOOOOOOOOOOOOOOOOOOOOOOOOOOOOOOOOOOOOOOOOOOOOOOOOOOOOOOOOOOOOOOOOOOOOOOOOOOOOOOOOOOOOOOO | OOOOOOOOOOOOOOOOOOOOOOOOOOOOOOOOOOOOOOOOOOOOOOOOOOOOOOOOOOOOOOOOOOOOOOOOOOOOOOOOOOOOOOOOOO | OOOOOOOOOOOOOOOOOOOOOOOOOOOOOOOOOOOOOOOOOOOOOOOOOOOOOOOOOOOOOOOOOOOOOOOOOOOOOOOOOOOOOOOOOO | OOOOOOOOOOOOOOOOOOOOOOOOOOOOOOOOOOOOOOOOOOOOOOOOOOOOOOOOOOOOOOOOOOOOOOOOOOOOOOOOOOOOOOOOOO | OOOOOOOOOOOOOOOOOOOOOOOOOOOOOOOOOOOOOOOOOOOOOOOOOOOOOOOOOOOOOOOOOOOOOOOOOOOOOOOOOOOOOOOOOO | OOOOOOOOOOOOOOOOOOOOOOOOOOOOOOOOOOOOOOOOOOOOOOOOOOOOOOOOOOOOOOOOOOOOOOOOOOOOOOOOOOOOOOOOOO |
| TLA Parts Change |  |  |  |  |  |  |  |  |  |
| Item | Foxconn P/N | Qty | Part Description | Manufacturer Full Name | Manufacturer P/N | RoHS | Location | Remark | BOM |
| BOM Change List Date:Fri Aug 25 09:35:09 CST 2017 |  |  |  |  |  |  |  |  |  |
| New BOM file : E:\barreleye g2\0824\foxbis\new BOM\FPDB 25.xls |  |  |  |  |  |  |  |  |  |
| Old BOM file : E:\barreleye g2\0824\foxbis\old bom\BG2-FPDB-0531.xls |  |  |  |  |  |  |  |  |  |
| ##### Add Parts |  |  |  |  |  |  |  |  |  |
| Item | Location | Qty | Foxconn P/N | Part Description | Manufacturer Full Name | Manufacturer P/N | RoHS | Sheet |  |
| 1 | C71,C72 | 2 | 620101T02-015-G | CAP,100nF,+/-10%,X7R,16V,G,SMD0402 | MURATA ELEC. NORTH AMERICA | GRM155R71C104K | G | PWA BOM |  |
|  |  |  | 620101T00-012-G | CAP,100nF,+/-10%,X7R,16V,G,SMD0402 | WALSIN TECHNOLOGY CORPORATION | 0402B104K160CT | G | PWA BOM |  |
|  |  |  | 620101T00-026-G | CAP,100nF,+/-10%,X7R,16V,G,SMD0402 | SAMSUNG SEMICONDUCTOR | CL05B104KO5NNNC | G | PWA BOM |  |
|  |  |  | 620101T00-015-G | CAP,100nF,+/-10%,X7R,16V,G,SMD0402 | MURATA ELEC. NORTH AMERICA | GRM155R71C104KA88D | G | PWA BOM |  |
| 2 | LED1,LED2 | 2 | 52113DU00-289-G | LED,Hyper Red,LTS-2307CKD-P,G,5V,25mA,G,SMD-10 | LITE-ON TECHNOLOGY CORPORATION | LTS-2307CKD-P | G | PWA BOM |  |
| 3 | PSUR2 | 1 | 610119C00-017-G | RES,130KOhm,+/-1%,1/16W,G,SMD0402 | KOA SPEER ELECTRONICS, INC. | RK73H1ETTP1303F | G | PWA BOM |  |
|  |  |  | 610119C00-011-G | RES,130KOhm,+/-1%,1/16W,G,SMD0402 | YAGEO CORPORATION COMPONENT | RC0402FR-07130KL | G | PWA BOM |  |
|  |  |  | 610119C00-012-G | RES,130KOhm,+/-1%,1/16W,G,SMD0402 | WALSIN TECHNOLOGY CORPORATION | WR04X1303FTL | G | PWA BOM |  |
|  |  |  | 610119C00-044-G | RES,130KOhm,+/-1%,1/16W,G,SMD0402 | TA-I TECHNOLOGY CO., LTD | RM04FTN1303 | G | PWA BOM |  |
| 4 | R251 | 1 | 61010L300-017-G | RES,1KOhm,+/-1%,1/16W,G,SMD0402 | KOA SPEER ELECTRONICS, INC. | RK73H1ETTP1001F | G | PWA BOM |  |
|  |  |  | 61010L300-012-G | RES,1KOhm,+/-1%,1/16W,G,SMD0402 | WALSIN TECHNOLOGY CORPORATION | WR04X1001FTL | G | PWA BOM |  |
|  |  |  | 61010L300-011-G | RES,1KOhm,+/-1%,1/16W,G,SMD0402 | YAGEO CORPORATION COMPONENT | RC0402FR-071KL | G | PWA BOM |  |
|  |  |  | 61010L300-044-G | RES,1KOhm,+/-1%,1/16W,G,SMD0402 | TA-I TECHNOLOGY CO., LTD. | RM04FTN1001 | G | PWA BOM |  |
|  |  |  | 61010L300-024-G | RES,1KOhm,+/-1%,1/16W,G,SMD0402 | PANASONIC INDUSTRIAL CO.,LTD. | ERJ2RKF1001X | G | PWA BOM |  |
|  |  |  | 61010L300-029-G | RES,1KOhm,+/-1%,1/16W,G,SMD0402 | VISHAY ENTER TECHNO LOGY.INC | CRCW04021K00FKED | G | PWA BOM |  |
| 5 | R252,R253,R254,R255,R256,R257,R258,R260,R261,R262,R263,R264,R265,R266,R267 | 15 | 61010JY00-017-G | RES,220 Ohm,+/-5%,1/16W,G,SMD0402 | KOA SPEER ELECTRONICS, INC. | RK73B1ETTP221J | G | PWA BOM |  |
|  |  |  | 61010JY00-012-G | RES,220 Ohm,+/-5%,1/16W,G,SMD0402 | WALSIN TECHNOLOGY CORPORATION | WR04X221JTL | G | PWA BOM |  |
|  |  |  | 61010JY00-011-G | RES,220 Ohm,+/-5%,1/16W,G,SMD0402 | YAGEO CORPORATION COMPONENT | RC0402JR-07220RL | G | PWA BOM |  |
|  |  |  | 61010JY00-044-G | RES,220 Ohm,+/-5%,1/16W,G,SMD0402 | TA-I TECHNOLOGY CO., LTD. | RM04JTN221 | G | PWA BOM |  |
| 6 | R250,R259 | 2 | 610107C00-017-G | RES,10KOhm,+/-5%,1/16W,G,SMD0402 | KOA SPEER ELECTRONICS, INC. | RK73B1ETTP103J | G | PWA BOM |  |
|  |  |  | 610107C00-012-G | RES,10KOhm,+/-5%,1/16W,G,SMD0402 | WALSIN TECHNOLOGY CORPORATION | WR04X103JTL | G | PWA BOM |  |
|  |  |  | 610107C00-011-G | RES,10KOhm,+/-5%,1/16W,G,SMD0402 | YAGEO CORPORATION COMPONENT | RC0402JR-0710KL | G | PWA BOM |  |
|  |  |  | 610107C00-044-G | RES,10KOhm,+/-5%,1/16W,G,SMD0402 | TA-I TECHNOLOGY CO., LTD | RM04JTN103 | G | PWA BOM |  |
|  |  |  | 610107C00-024-G | RES,10KOhm,+/-5%,1/16W,G,SMD0402 | PANASONIC INDUSTRIAL CO.,LTD. | ERJ2GEJ103X | G | PWA BOM |  |
|  |  |  | 610107C00-029-G | RES,10KOhm,+/-5%,1/16W,G,SMD0402 | VISHAY ENTER TECHNO LOGY.INC | CRCW040210K0JNED | G | PWA BOM |  |
| 7 | U25,U26 | 2 | 310200R00-183-G | IC,Trigger,SN74LV164ADBR,2~5.5V,G,SSOP-14,SMD | TEXAS INSTRUMENTS | SN74LV164ADBR | G | PWA BOM |  |
| 8 | J10 | 1 | 3406ARH00-309-G | CONN,Header,Socket,V/T,Bla,2.54mm,10u,G,DIP-8 | SAMTEC INC. | ESQ-104-33-L-D | G | PWA BOM |  |
| ##### Remove Parts |  |  |  |  |  |  |  |  |  |
| Item | Location | Qty | Foxconn P/N | Part Description | Manufacturer Full Name | Manufacturer P/N | RoHS | Sheet |  |
| 1 | PSUR2,PEUR7 | 2 | 610116G00-017-G | RES,150KOhm,+/-1%,1/16W,G,SMD0402 | KOA SPEER ELECTRONICS, INC. | RK73H1ETTP1503F | G | PWA BOM |  |
|  |  |  | 610116G00-011-G | RES,150KOhm,+/-1%,1/16W,G,SMD0402 | YAGEO CORPORATION COMPONENT | RC0402FR-07150KL | G | PWA BOM |  |
|  |  |  | 610116G00-012-G | RES,150KOhm,+/-1%,1/16W,G,SMD0402 | WALSIN TECHNOLOGY CORPORATION | WR04X1503FTL | G | PWA BOM |  |
|  |  |  | 610116G00-044-G | RES,150KOhm,+/-1%,1/16W,G,SMD0402 | TA-I TECHNOLOGY CO., LTD | RM04FTN1503 | G | PWA BOM |  |
| 2 | PHAR33 | 1 | 610107A00-017-G | RES,0 Ohm,+/-5%,1/16W,G,SMD0402 | KOA SPEER ELECTRONICS, INC. | RK73Z1ETTP | G | PWA BOM |  |
|  |  |  | 610107A00-012-G | RES,0 Ohm,+/-5%,1/16W,G,SMD0402 | WALSIN TECHNOLOGY CORPORATION | WR04X000PTL | G | PWA BOM |  |
|  |  |  | 610107A00-011-G | RES,0 Ohm,+/-5%,1/16W,G,SMD0402 | YAGEO CORPORATION COMPONENT | RC0402JR-070RL | G | PWA BOM |  |
|  |  |  | 610107A00-044-G | RES,0 Ohm,+/-5%,1/16W,G,SMD0402 | TA-I TECHNOLOGY CO., LTD. | RM04JTN0 | G | PWA BOM |  |
|  |  |  | 610107A00-024-G | RES,0 Ohm,+/-5%,1/16W,G,SMD0402 | PANASONIC INDUSTRIAL CO.,LTD. | ERJ2GE0R00X | G | PWA BOM |  |
|  |  |  | 610107A00-029-G | RES,0 Ohm,+/-5%,1/16W,G,SMD0402 | VISHAY ENTER TECHNO LOGY.INC | CRCW04020000Z0ED | G | PWA BOM |  |
| 3 | PSUR4,PEUR6 | 2 | 610118S00-017-G | RES,54.9KOhm,+/-1%,1/16W,G,SMD0402 | KOA SPEER ELECTRONICS, INC. | RK73H1ETTP5492F | G | PWA BOM |  |
|  |  |  | 610118S00-011-G | RES,54.9KOhm,+/-1%,1/16W,G,SMD0402 | YAGEO CORPORATION COMPONENT | RC0402FR-0754K9L | G | PWA BOM |  |
|  |  |  | 610118S00-012-G | RES,54.9KOhm,+/-1%,1/16W,G,SMD0402 | WALSIN TECHNOLOGY CORPORATION | WR04X5492FTL | G | PWA BOM |  |
|  |  |  | 610118S00-044-G | RES,54.9KOhm,+/-1%,1/16W,G,SMD0402 | TA-I TECHNOLOGY CO., LTD. | RM04FTN5492 | G | PWA BOM |  |
| 4 | PSUR5 | 1 | 61011N000-017-G | RES,68KOhm,+/-1%,1/16W,G,SMD0402 | KOA SPEER ELECTRONICS, INC. | RK73H1ETTP6802F | G | PWA BOM |  |
| 5 | PSUSW1,PEUSW1 | 2 | 34080F500-653-G | CONN,Switch,slide,25mA,24V,G,SMD-8 | DIPTRONICS MANUFACTURING INC. | DHN-04F-T-V-T/R | G | PWA BOM |  |
| ##### Change Parts |  |  |  |  |  |  |  |  |  |
| Item | Location | Qty | Foxconn P/N | Part Description | Manufacturer Full Name | Manufacturer P/N | RoHS | Sheet | Remark |
| 1 | PSUU1,PEUU1 | 2 | 880302300-065-G | Converter,input 40V~60V,600W,G,Q54SJ12050NNDH | DELTA ELECTRONICS INDUSTRIAL CO.,LTD | Q54SJ12050NNDH | G | PWA BOM | In New BOM |
|  |  |  | 880302100-065-G | Converter,input 40V~60V,600W,G,Q54SH12050NNDH | DELTA ELECTRONICS INDUSTRIAL CO.,LTD | Q54SH12050NNDH | G | PWA BOM | In New BOM |
|  | PSUU1,PEUU1 | 2 | 880302300-065-G | Converter,input 40V~60V,600W,G,Q54SJ12050NNDH | DELTA ELECTRONICS INDUSTRIAL CO.,LTD | Q54SJ12050NNDH | G | PWA BOM | In Old BOM |
|  |  |  | 880302100-065-G | Converter,input 40V~60V,600W,G,Q54SH12050NNDH | DELTA ELECTRONICS INDUSTRIAL CO.,LTD | Q54SH12050NNDH |  | PWA BOM | In Old BOM |
| 2 | PHAQ1,PHAQ2,PHAQ3 | 3 | 51031VY00-031-G | MOS N,PSMN4R8-100BSE,100V,120A,4.8m@10V,G,SOT404-3,SMD | NXP SEMICONDUCTORS | PSMN4R8-100BSE | G | PWA BOM | In New BOM |
|  |  |  | 51032JY00-029-G | MOS N,SUM70040E-GE3,100V,120A,G,TO-263-3,SMD | VISHAY ENTER TECHNO LOGY.INC | SUM70040E-GE3 | G | PWA BOM | In New BOM |
|  |  |  | 51032HE00-185-G | MOS N,FDB047N10,100V,120A,3.9m@10V,G,TO263-3,SMD | FAIRCHILD SEMICONDUCTOR CORP | FDB047N10 | G | PWA BOM | In New BOM |
|  | PHAQ1,PHAQ2,PHAQ3 | 3 | 51031VY00-031-G | MOS N,PSMN4R8-100BSE,100V,120A,4.8m@10V,G,SOT404-3,SMD | NXP SEMICONDUCTORS | PSMN4R8-100BSE | G | PWA BOM | In Old BOM |
|  |  |  | SUM70040E-GE3 | MOS N,SUM70040E-GE3 | VISHAY ENTER TECHNO LOGY.INC | SUM70040E-GE3 | G | PWA BOM | In Old BOM |
|  |  |  | FDB047N10 | MOS N,FDB047N10 | FAIRCHILD SEMICONDUCTOR CORP | FDB047N10 | G | PWA BOM | In Old BOM |
| 3 | PHAQ4 | 1 | 51020A000-031-G | TRANS P,PBHV9115T,150V,1A,G,SOT23-3,SMD | NXP SEMICONDUCTORS | PBHV9115T | G | PWA BOM | In New BOM |
|  |  |  | 51020BJ00-185-G | Trans PNP,MMBT5401,-150V,-600mA,G,SOT-23-3,SMD | FAIRCHILD SEMICONDUCTOR CORP | MMBT5401 | G | PWA BOM | In New BOM |
|  |  |  | 510204N00-237-G | Trans PNP,MMBT5401-7-F,-150V,-600mA,SOT-23,3P,G | DIODES INCORPORATION | MMBT5401-7-F | G | PWA BOM | In New BOM |
|  | PHAQ4 | 1 | 51020A000-031-G | TRANS P,PBHV9115T,150V,1A,G,SOT23-3,SMD | NXP SEMICONDUCTORS | PBHV9115T | G | PWA BOM | In Old BOM |
|  |  |  | MMBT5401 | TRANS,150V,1A,G,SOT23-3,SMD | FAIRCHILD SEMICONDUCTOR CORP | MMBT5401 | G | PWA BOM | In Old BOM |
|  |  |  | 510204N00-237-G | Trans PNP,MMBT5401-7-F,-150V,-600mA,SOT-23,3P,G | DIODES INCORPORATION | MMBT5401-7-F | G | PWA BOM | In Old BOM |
| 4 | PHAQ5,PHAQ9 | 2 | 51032D100-237-G | MOS N,DMN10H220L-7,100V,1.6A,220m@10V,G,SOT-23-3,SMD | DIODES INCORPORATION | DMN10H220L-7 | G | PWA BOM | In New BOM |
|  | PHAQ5,PHAQ9 | 2 | 51032D100-237-G | MOS N,DMN10H220L-7,100V,1.6A,220m@10V,G,SOT-23-3,SMD | DIODES INCORPORATION | DMN10H220L-7 | G | PWA BOM | In Old BOM |
|  |  |  | FQT7N10LTF | MOS N,FQT7N10LTF | FAIRCHILD SEMICONDUCTOR CORP | FQT7N10LTF | G | PWA BOM | In Old BOM |
| 5 | PSRC4 | 1 | 62012T300-015-G | CAP,1uF,+/-10%,X7S,25V,G,SMD0402 | MURATA ELEC. NORTH AMERICA | GRM155C71E105KE11D | G | PWA BOM | In New BOM |
|  |  |  | 620138700-026-G | CAP,1uF,+/-10%,X6S,25V,G,SMD0402 | SAMSUNG SEMICONDUCTOR | CL05X105KA5NQNC | G | PWA BOM | In New BOM |
|  |  |  | 620138700-015-G | CAP,1uF,+/-10%,X6S,25V,G,SMD0402 | MURATA | GRM155C81E105KE11D | G | PWA BOM | In New BOM |
|  | PSRC4 | 1 | 62012T300-015-G | CAP,1uF,+/-10%,X7S,25V,G,SMD0402 | MURATA ELEC. NORTH AMERICA | GRM155C71E105KE11D | G | PWA BOM | In Old BOM |
| 6 | PSRL2 | 1 | 63032PP00-088-G | IND,4.7uH@100KHz,+/-20%,5.5A,40mOhm,SHLD,G,SMD | COOPER BUSSMANN, INC. | HCM0703-4R7-R | G | PWA BOM | In New BOM |
|  |  |  | 63030PW00-034-G | Coil Ind,Shielded(SHLD),4.7uH@100KHz,+/-20%,5.5A,40mOhm,SMD,7.3*6.6*3.0,G | CYNTEC CO. LTD | PCMC063T-4R7MN | G | PWA BOM | In New BOM |
|  |  |  | 63031AD04-129-G | IND,4.7uH@100KHz,+/-20%,5.5A,40mOhm,SHLD,G,SMD | MAG.LAYERS, SCIENTIFIC-TECHNICS (KUNSHAN) CO., LTD. | SPS-06CZ-4R7M-V1 | G | PWA BOM | In New BOM |
|  | PSRL2 | 1 | 63032PP00-088-G | IND,4.7uH@100KHz,+/-20%,5.5A,40mOhm,SHLD,G,SMD | COOPER BUSSMANN, INC. | HCM0703-4R7-R | G | PWA BOM | In Old BOM |
|  |  |  | 63030PW00-034-G | Coil Ind,Shielded(SHLD),4.7uH@100KHz,+/-20%,5.5A,40mOhm,SMD,7.3*6.6*3.0,G | CYNTEC CO. LTD | PCMC063T-4R7MN | G | PWA BOM | In Old BOM |
|  |  |  | SPS-06CZ-4R7M-V1 | IND,SPS-06CZ-4R7M-V1 | MAG.LAYERS, SCIENTIFIC-TECHNICS (KUNSHAN) CO., LTD. | SPS-06CZ-4R7M-V1 | G | PWA BOM | In Old BOM |
| 7 | QN4 | 1 | 510503B00-223-G | MOS N/N,NTZD3154NT1G,20V,0.54A,550m24.5V,G,SOT563-6,SMD | ON SEMICONDUCTOR CORP | NTZD3154NT1G | G | PWA BOM | In New BOM |
|  |  |  | 51050L500-029-G | MOS,N/N,Si1034CX-T1-GE3,20V,0.61A,G,SC-89-6,SMD | VISHAY ENTER TECHNO LOGY.INC | Si1034CX-T1-GE3 | G | PWA BOM | In New BOM |
|  |  |  | 51050KW00-131-G | MOS N/N,SSM6N36FE,20V,500mA,0.63@5V,G,ES6-6,SMD | TOSHIBA ELECTRONICS ASIA LTD | SSM6N36FE | G | PWA BOM | In New BOM |
|  | QN4 | 1 | 510503B00-223-G | MOS N/N,NTZD3154NT1G,20V,0.54A,550m24.5V,G,SOT563-6,SMD | ON SEMICONDUCTOR CORP | NTZD3154NT1G | G | PWA BOM | In Old BOM |
|  |  |  | Si1034CX-T1-GE3 | MOS N/N,Si1034CX-T1-GE3 | VISHAY ENTER TECHNO LOGY.INC | Si1034CX-T1-GE3 | G | PWA BOM | In Old BOM |
|  |  |  | SSM6N36FE | MOS N/N,SSM6N36FE | TOSHIBA ELECTRONICS ASIA LTD | SSM6N36FE | G | PWA BOM | In Old BOM |
| 8 | U110 | 1 | 330103N00-426-G | IC,Optocoupler,PS2811-1-F3-A,G,SSOP-4,SMD | RENESAS TECHNOLOGY AMERICA INC | PS2811-1-F3-A | G | PWA BOM | In New BOM |
|  |  |  | 330102900-289-G | OPTO-IC,ISOL,LTV-217-G,SSOP,4P,G | LITE-ON TECHNOLOGY CORPORATION | LTV-217-G | G | PWA BOM | In New BOM |
|  |  |  | 330103T00-029-G | IC,Optocoupler,VOS618A-3X001T,G,SSOP-4,SMD | VISHAY ENTER TECHNO LOGY.INC | VOS618A-3X001T | G | PWA BOM | In New BOM |
|  | U110 | 1 | 330103N00-426-G | IC,Optocoupler,PS2811-1-F3-A,G,SSOP-4,SMD | RENESAS TECHNOLOGY AMERICA INC | PS2811-1-F3-A | G | PWA BOM | In Old BOM |
|  |  |  | 330102900-289-G | OPTO-IC,ISOL,LTV-217-G,SSOP,4P,G | LITE-ON TECHNOLOGY CORPORATION | LTV-217-G | G | PWA BOM | In Old BOM |
|  |  |  | VOS618A-3T | OPTO-IC,VOS618A-3T | VISHAY ENTER TECHNO LOGY.INC | VOS618A-3T | G | PWA BOM | In Old BOM |
| 9 | Y1,Y2 | 2 | 71020KL00-100-G | OSC,33MHz,+/-50ppm,3.3V,15pF,G,SMD | TXC CORPORATION | 7X33000013 | G | PWA BOM | In New BOM |
|  |  |  | 710211800-967-G | OSC,33MHz,+/-50ppm,3.3V,15pF,G,SMD | eCERA | FK3300011 | G | PWA BOM | In New BOM |
|  |  |  | 710216N00-873-G | OSC,33MHz,+/-50ppm,3.3V,15pF,G,SMD | Kyocera | KC3225K33.0000C10E00 | G | PWA BOM | In New BOM |
|  | Y1,Y2 | 2 | 71020KL00-100-G | OSC,33MHz,+/-50ppm,3.3V,15pF,G,SMD | TXC CORPORATION | 7X33000013 | G | PWA BOM | In Old BOM |
| 10 | PCB | 1 | PCB | PCB | PCB | PCB | G | PWA BOM | In New BOM |
|  | PCB | 1 | 0101F1100-000-G | PCB,Zaius-FPDB DVT-X01,OSP,Blu,6L,18.2623*7.025,G | GOLD CIRCUIT ELECTRONICS LTD. | 0101F1100-000-G | G | PWA BOM | In Old BOM |
| 11 | D1,D2,D3,D4,D5,PHAD6,D6,D7,D8,D9,D10,D11,D12 | 13 | 520100200-237-G | DIODE,Switching,1N4148W-7-F,100V,0.15A,G,SOD123-2,SMD | DIODES INEORPORATION | 1N4148W-7-F | G | PWA BOM | In New BOM |
|  |  |  | 520102P00-031-G | DIODE,Switching,BAS16H,100V,0.5A,G,SOD123F-2,SMD | NXP SEMICONDUCTORS | BAS16H | G | PWA BOM | In New BOM |
|  | D1,D2,D3,D4,D5,PHAD6,D6,D7,D8,D9,D10,D11,D12 | 13 | 520100200-237-G | DIODE,Switching,1N4148W-7-F,100V,0.15A,G,SOD123-2,SMD | DIODES INCORPORATION | 1N4148W-7-F | G | PWA BOM | In Old BOM |
|  |  |  | 520102P00-031-G | DIODE,Switching,BAS16H,100V,0.5A,G,SOD123F-2,SMD | NXP SEMICONDUCTORS | BAS16H | G | PWA BOM | In Old BOM |
| 12 | D34 | 1 | 520401Y00-237-G | DIODE,Zener,BZT52C3V6-7-F,3.6V,5mA,G,SOD123-2,SMD | DIODES INEORPORATION | BZT52C3V6-7-F | G | PWA BOM | In New BOM |
|  |  |  | 520407600-223-G | Diode,ZENER,MMSZ3V6T1G,3.6V,5mA,SOD-123,2P,G | ON SEMICONDUCTOR CORP | MMSZ3V6T1G | G | PWA BOM | In New BOM |
|  | D34 | 1 | 520401Y00-237-G | DIODE,Zener,BZT52C3V6-7-F,3.6V,5mA,G,SOD123-2,SMD | DIODES INCORPORATION | BZT52C3V6-7-F | G | PWA BOM | In Old BOM |
|  |  |  | 520407600-223-G | Diode,ZENER,MMSZ3V6T1G,3.6V,5mA,SOD-123,2P,G | ON SEMICONDUCTOR CORP | MMSZ3V6T1G | G | PWA BOM | In Old BOM |
| 13 | FS4,FS5,FS6,FS7,FS8,FS9 | 6 | 0438005.WRGT | Fuse,Fast acting,32V,5A,G,SMD0603 | LITTELFUSE FAR EAST PTE LTD | 0438005.WRGT | G | PWA BOM | In New BOM |
|  |  |  | 730103M00-086-G | Fuse,Fast acting,32V,5A,G,SMD0603 | LITTELFUSE FAR EAST PTE LTD | 0438005.WR | G | PWA BOM | In New BOM |
|  |  |  | 730103M00-088-G | Fuse,Fast acting,32V,5A,SMD0603,G | COOPER BUSSMANN, INC. | CC06H5A-TR | G | PWA BOM | In New BOM |
|  | FS4,FS5,FS6,FS7,FS8,FS9 | 6 | 730103M00-086-G | Fuse,Fast acting,32V,5A,G,SMD0603 | LITTELFUSE FAR EAST PTE LTD | 0438005.WR | G | PWA BOM | In Old BOM |
|  |  |  | 730103M00-088-G | Fuse,Fast acting,32V,5A,SMD0603,G | COOPER BUSSMANN, INC. | CC06H5A-TR | G | PWA BOM | In Old BOM |
| 14 | J4,J5,J6,J7,J8,J9 | 6 | 22-23-2081 | CONN,Header,WTB,1X8,V/T,Bla,2.54mm,G,DIP-8 | MOLEX INCORPORATED | 22-23-2081 | G | PWA BOM | In New BOM |
|  | J4,J5,J6,J7,J8,J9 | 6 | 340699J00-317-G | CONN,Header,WTB,1X8,V/T,Bla,2.54mm,G,DIP-8 | MOLEX INCORPORATED | 22-23-2081 | G | PWA BOM | In Old BOM |
| 15 | PHAD3 | 1 | 52040EC00-237-G | DIODE,Zener,MMSZ5246B-7-F,16V,7.8mA,G,SOD123-2,SMD | DIODES INEORPORATION | MMSZ5246B-7-F | G | PWA BOM | In New BOM |
|  |  |  | 52040B500-223-G | DIODE,Zener,MMSZ5246BT1G,16V,7.8mA,G,SOD123-2,SMD | ON SEMICONDUCTOR CORP | MMSZ5246BT1G | G | PWA BOM | In New BOM |
|  |  |  | 52040EY00-031-G | Diode,ZENER,BZT52H-C16,17.1V,5mA,G,SOD123F-2,SMD | NXP SEMICONDUCTORS | BZT52H-C16 | G | PWA BOM | In New BOM |
|  | PHAD3 | 1 | 52040EC00-237-G | DIODE,Zener,MMSZ5246B-7-F,16V,7.8mA,G,SOD123-2,SMD | DIODES INCORPORATION | MMSZ5246B-7-F | G | PWA BOM | In Old BOM |
|  |  |  | 52040B500-223-G | DIODE,Zener,MMSZ5246BT1G,16V,7.8mA,G,SOD123-2,SMD | ON SEMICONDUCTOR CORP | MMSZ5246BT1G | G | PWA BOM | In Old BOM |
|  |  |  | 52040EY00-031-G | Diode,ZENER,BZT52H-C16,17.1V,5mA,G,SOD123F-2,SMD | NXP SEMICONDUCTORS | BZT52H-C16 | G | PWA BOM | In Old BOM |
| 16 | PHAQ8 | 1 | 510100W00-237-G | TRANS N,MMBT3904-7-F,40V,0.2A,G,SOT23-3,SMD | DIODES INEORPORATION | MMBT3904-7-F | G | PWA BOM | In New BOM |
|  |  |  | 510101700-185-G | TRANS N,MMBT3904,40V,0.2A,G,SOT23-3,SMD | FAIRCHILD SEMICONDUCTOR CORP | MMBT3904 | G | PWA BOM | In New BOM |
|  |  |  | 510100800-223-G | TRANS N,MMBT3904LT1G,40V,0.2A,G,SOT23-3,SMD | ON SEMICONDUCTOR CORP | MMBT3904LT1G | G | PWA BOM | In New BOM |
|  |  |  | 510100500-031-G | TRANS N,PMBT3904,40V,0.2A,G,SOT23-3,SMD | NXP SEMICONDUCTORS | PMBT3904 | G | PWA BOM | In New BOM |
|  | PHAQ8 | 1 | 510100W00-237-G | TRANS N,MMBT3904-7-F,40V,0.2A,G,SOT23-3,SMD | DIODES INCORPORATION | MMBT3904-7-F | G | PWA BOM | In Old BOM |
|  |  |  | 510101700-185-G | TRANS N,MMBT3904,40V,0.2A,G,SOT23-3,SMD | FAIRCHILD SEMICONDUCTOR CORP | MMBT3904 | G | PWA BOM | In Old BOM |
|  |  |  | 510100800-223-G | TRANS N,MMBT3904LT1G,40V,0.2A,G,SOT23-3,SMD | ON SEMICONDUCTOR CORP | MMBT3904LT1G | G | PWA BOM | In Old BOM |
|  |  |  | 510100500-031-G | TRANS N,PMBT3904,40V,0.2A,G,SOT23-3,SMD | NXP SEMICONDUCTORS | PMBT3904 | G | PWA BOM | In Old BOM |
| 17 | PHAR1 | 1 | 610601801-32D-G | RES,0.5mOhm,+/-1%,2W,G,SMD1225 | Thin Film Technology Corporation | CPA1225R0M50FW-T5 | G | PWA BOM | In New BOM |
|  | PHAR1 | 1 | 610601800-32D-G | RES,0.5mOhm,+/-1%,2W,G,SMD1225 | Thin Film Technology Corporation | CPA1225R0M50FW-T5 | G | PWA BOM | In Old BOM |
| 18 | PEUR2 | 1 | 61010G500-017-G | RES,10KOhm,+/-1%,1/16W,G,SMD0402 | KOA SPEER ELECTRONICS, INC. | RK73H1ETTP1002F | G | PWA BOM | In New BOM |
|  |  |  | 61010G500-012-G | RES,10KOhm,+/-1%,1/16W,G,SMD0402 | WALSIN TECHNOLOGY CORPORATION | WR04X1002FTL | G | PWA BOM | In New BOM |
|  |  |  | 61010G500-011-G | RES,10KOhm,+/-1%,1/16W,G,SMD0402 | YAGEO CORPORATION COMPONENT | RC0402FR-0710KL | G | PWA BOM | In New BOM |
|  |  |  | 61010G500-044-G | RES,10KOhm,+/-1%,1/16W,G,SMD0402 | TA-I TECHNOLOGY CO., LTD. | RM04FTN1002 | G | PWA BOM | In New BOM |
|  |  |  | 61010G500-029-G | RES,10KOhm,+/-1%,1/16W,G,SMD0402 | VISHAY ENTER TECHNO LOGY.INC | CRCW040210K0FKED | G | PWA BOM | In New BOM |
|  |  |  | 61010G500-024-G | RES,10KOhm,+/-1%,1/16W,G,SMD0402 | PANASONIC INDUSTRIAL CO.,LTD. | ERJ2RKF1002X | G | PWA BOM | In New BOM |
|  | PEUR2 | 1 | 610116G00-017-G | RES,150KOhm,+/-1%,1/16W,G,SMD0402 | KOA SPEER ELECTRONICS, INC. | RK73H1ETTP1503F | G | PWA BOM | In Old BOM |
|  |  |  | 610116G00-011-G | RES,150KOhm,+/-1%,1/16W,G,SMD0402 | YAGEO CORPORATION COMPONENT | RC0402FR-07150KL | G | PWA BOM | In Old BOM |
|  |  |  | 610116G00-012-G | RES,150KOhm,+/-1%,1/16W,G,SMD0402 | WALSIN TECHNOLOGY CORPORATION | WR04X1503FTL | G | PWA BOM | In Old BOM |
|  |  |  | 610116G00-044-G | RES,150KOhm,+/-1%,1/16W,G,SMD0402 | TA-I TECHNOLOGY CO., LTD | RM04FTN1503 | G | PWA BOM | In Old BOM |
| 19 | U_FPDB_FRU | 1 | 41040J500-232-G | EEPROM,24AA024T-I/SN,1.7V~5.5V,2K,I2C,G,SOIC-8,SMD | MICROCHIP TECHNOLOGY INC | 24AA024T-I/SN | G | PWA BOM | In New BOM |
|  | U_FPDB_FRU | 1 | 41040HW00-191-G | EEPROM,AT24C02D-SSHM-T,1.7~3.6V,2K,I2C,G,SOIC-8,SMD | ATMEL CORPORATION | AT24C02D-SSHM-T | G | PWA BOM | In Old BOM |
|  |  |  | 410401W00-214-G | EEPROM,M24C02-WMN6TP,2.5~5.5V,256*8,I2C,G,SOIC-8,SMD | ST MICRO ELECTRONICS,INC | M24C02-WMN6TP | G | PWA BOM | In Old BOM |
|  |  |  | 41040CW00-232-G | EEPROM,24AA024-I/SN,1.7~5.5V,2K,I2C,G,SOIC-8,SMD | MICROCHIP TECHNOLOGY INC | 24AA024-I/SN | G | PWA BOM | In Old BOM |
| 20 | J1 | 1 | 3406A1800-317-G | CONN,Header,WTB,1X8,V/T,Bla,2.54mm,G,DIP-8 | MOLEX INCORPORATED | 171856-0108 | G | PWA BOM | In New BOM |
|  | J1 | 1 | 3406ANQ00-317-G | CONN,Header,Power,V/T,Bla,10mm,30u,G,DIP-8 | MOLEX INCORPORATED | 42819-4213 | G | PWA BOM | In Old BOM |
| 21 | PSUR1 | 1 | 61011GD00-017-G | RES,15.4KOhm,+/-1%,1/16W,G,SMD0402 | KOA SPEER ELECTRONICS, INC. | RK73H1ETTP1542F | G | PWA BOM | In New BOM |
|  |  |  | 61011GD00-011-G | RES,15.4KOhm,+/-1%,1/16W,G,SMD0402 | YAGEO CORPORATION COMPONENT | RC0402FR-0715K4L | G | PWA BOM | In New BOM |
|  |  |  | 61011GD00-012-G | RES,15.4KOhm,+/-1%,1/16W,G,SMD0402 | WALSIN TECHNOLOGY CORPORATION | WR04X1542FTL | G | PWA BOM | In New BOM |
|  |  |  | 61011GD00-044-G | RES,15.4KOhm,+/-1%,1/16W,G,SMD0402 | TA-I TECHNOLOGY CO., LTD. | RM04FTN1542 | G | PWA BOM | In New BOM |
|  | PSUR1 | 1 | 61011NY00-017-G | RES,88.7KOhm,+/-1%,1/16W,G,SMD0402 | KOA SPEER ELECTRONICS, INC. | RK73H1ETTP8872F | G | PWA BOM | In Old BOM |
| ##### Change Revision |  |  |  |  |  |  |  |  |  |
| Sheet | REV OF BOM | CUSTOMER | CUSTOMER P/N | PWA PN | PWA DESCRIPTION | PWA REV | DATE | Remark |  |
| OOOOOOOOOOOOOOOOOOOOOOOOOOOOOOOOOOOOOOOOOOOOOOOOOOOOOOOOOOOOOOOOOOOOOOOOOOOOOOOOOOOOOOOOOO | OOOOOOOOOOOOOOOOOOOOOOOOOOOOOOOOOOOOOOOOOOOOOOOOOOOOOOOOOOOOOOOOOOOOOOOOOOOOOOOOOOOOOOOOOO | OOOOOOOOOOOOOOOOOOOOOOOOOOOOOOOOOOOOOOOOOOOOOOOOOOOOOOOOOOOOOOOOOOOOOOOOOOOOOOOOOOOOOOOOOO | OOOOOOOOOOOOOOOOOOOOOOOOOOOOOOOOOOOOOOOOOOOOOOOOOOOOOOOOOOOOOOOOOOOOOOOOOOOOOOOOOOOOOOOOOO | OOOOOOOOOOOOOOOOOOOOOOOOOOOOOOOOOOOOOOOOOOOOOOOOOOOOOOOOOOOOOOOOOOOOOOOOOOOOOOOOOOOOOOOOOO | OOOOOOOOOOOOOOOOOOOOOOOOOOOOOOOOOOOOOOOOOOOOOOOOOOOOOOOOOOOOOOOOOOOOOOOOOOOOOOOOOOOOOOOOOO | OOOOOOOOOOOOOOOOOOOOOOOOOOOOOOOOOOOOOOOOOOOOOOOOOOOOOOOOOOOOOOOOOOOOOOOOOOOOOOOOOOOOOOOOOO | OOOOOOOOOOOOOOOOOOOOOOOOOOOOOOOOOOOOOOOOOOOOOOOOOOOOOOOOOOOOOOOOOOOOOOOOOOOOOOOOOOOOOOOOOO | OOOOOOOOOOOOOOOOOOOOOOOOOOOOOOOOOOOOOOOOOOOOOOOOOOOOOOOOOOOOOOOOOOOOOOOOOOOOOOOOOOOOOOOOOO | OOOOOOOOOOOOOOOOOOOOOOOOOOOOOOOOOOOOOOOOOOOOOOOOOOOOOOOOOOOOOOOOOOOOOOOOOOOOOOOOOOOOOOOOOO |
| Second Source Change |  |  |  |  |  |  |  |  |  |
| Item | Location | Change Type | Foxconn P/N | Part Description | Manufacturer Full Name | Manufacturer P/N | RoHS | Sheet |  |
| 1 | PHAQ1,PHAQ2,PHAQ3 |  | 51031VY00-031-G | MOS N,PSMN4R8-100BSE,100V,120A,4.8m@10V,G,SOT404-3,SMD | NXP SEMICONDUCTORS | PSMN4R8-100BSE | G | PWA BOM |  |
|  |  | ADD | 51032JY00-029-G | MOS N,SUM70040E-GE3,100V,120A,G,TO-263-3,SMD | VISHAY ENTER TECHNO LOGY.INC | SUM70040E-GE3 | G | PWA BOM |  |
|  |  | ADD | 51032HE00-185-G | MOS N,FDB047N10,100V,120A,3.9m@10V,G,TO263-3,SMD | FAIRCHILD SEMICONDUCTOR CORP | FDB047N10 | G | PWA BOM |  |
|  |  | Delete | SUM70040E-GE3 | MOS N,SUM70040E-GE3 | VISHAY ENTER TECHNO LOGY.INC | SUM70040E-GE3 | G | PWA BOM |  |
|  |  | Delete | FDB047N10 | MOS N,FDB047N10 | FAIRCHILD SEMICONDUCTOR CORP | FDB047N10 | G | PWA BOM |  |
| 2 | PHAQ4 |  | 51020A000-031-G | TRANS P,PBHV9115T,150V,1A,G,SOT23-3,SMD | NXP SEMICONDUCTORS | PBHV9115T | G | PWA BOM |  |
|  |  | ADD | 51020BJ00-185-G | Trans PNP,MMBT5401,-150V,-600mA,G,SOT-23-3,SMD | FAIRCHILD SEMICONDUCTOR CORP | MMBT5401 | G | PWA BOM |  |
|  |  | NO | 510204N00-237-G | Trans PNP,MMBT5401-7-F,-150V,-600mA,SOT-23,3P,G | DIODES INCORPORATION | MMBT5401-7-F | G | PWA BOM |  |
|  |  | Delete | MMBT5401 | TRANS,150V,1A,G,SOT23-3,SMD | FAIRCHILD SEMICONDUCTOR CORP | MMBT5401 | G | PWA BOM |  |
| 3 | PHAQ5,PHAQ9 |  | 51032D100-237-G | MOS N,DMN10H220L-7,100V,1.6A,220m@10V,G,SOT-23-3,SMD | DIODES INCORPORATION | DMN10H220L-7 | G | PWA BOM |  |
|  |  | Delete | FQT7N10LTF | MOS N,FQT7N10LTF | FAIRCHILD SEMICONDUCTOR CORP | FQT7N10LTF | G | PWA BOM |  |
| 4 | PSRC4 |  | 62012T300-015-G | CAP,1uF,+/-10%,X7S,25V,G,SMD0402 | MURATA ELEC. NORTH AMERICA | GRM155C71E105KE11D | G | PWA BOM |  |
|  |  | ADD | 620138700-026-G | CAP,1uF,+/-10%,X6S,25V,G,SMD0402 | SAMSUNG SEMICONDUCTOR | CL05X105KA5NQNC | G | PWA BOM |  |
|  |  | ADD | 620138700-015-G | CAP,1uF,+/-10%,X6S,25V,G,SMD0402 | MURATA | GRM155C81E105KE11D | G | PWA BOM |  |
| 5 | PSRL2 |  | 63032PP00-088-G | IND,4.7uH@100KHz,+/-20%,5.5A,40mOhm,SHLD,G,SMD | COOPER BUSSMANN, INC. | HCM0703-4R7-R | G | PWA BOM |  |
|  |  | NO | 63030PW00-034-G | Coil Ind,Shielded(SHLD),4.7uH@100KHz,+/-20%,5.5A,40mOhm,SMD,7.3*6.6*3.0,G | CYNTEC CO. LTD | PCMC063T-4R7MN | G | PWA BOM |  |
|  |  | ADD | 63031AD04-129-G | IND,4.7uH@100KHz,+/-20%,5.5A,40mOhm,SHLD,G,SMD | MAG.LAYERS, SCIENTIFIC-TECHNICS (KUNSHAN) CO., LTD. | SPS-06CZ-4R7M-V1 | G | PWA BOM |  |
|  |  | Delete | SPS-06CZ-4R7M-V1 | IND,SPS-06CZ-4R7M-V1 | MAG.LAYERS, SCIENTIFIC-TECHNICS (KUNSHAN) CO., LTD. | SPS-06CZ-4R7M-V1 | G | PWA BOM |  |
| 6 | QN4 |  | 510503B00-223-G | MOS N/N,NTZD3154NT1G,20V,0.54A,550m24.5V,G,SOT563-6,SMD | ON SEMICONDUCTOR CORP | NTZD3154NT1G | G | PWA BOM |  |
|  |  | ADD | 51050L500-029-G | MOS,N/N,Si1034CX-T1-GE3,20V,0.61A,G,SC-89-6,SMD | VISHAY ENTER TECHNO LOGY.INC | Si1034CX-T1-GE3 | G | PWA BOM |  |
|  |  | ADD | 51050KW00-131-G | MOS N/N,SSM6N36FE,20V,500mA,0.63@5V,G,ES6-6,SMD | TOSHIBA ELECTRONICS ASIA LTD | SSM6N36FE | G | PWA BOM |  |
|  |  | Delete | Si1034CX-T1-GE3 | MOS N/N,Si1034CX-T1-GE3 | VISHAY ENTER TECHNO LOGY.INC | Si1034CX-T1-GE3 | G | PWA BOM |  |
|  |  | Delete | SSM6N36FE | MOS N/N,SSM6N36FE | TOSHIBA ELECTRONICS ASIA LTD | SSM6N36FE | G | PWA BOM |  |
| 7 | U110 |  | 330103N00-426-G | IC,Optocoupler,PS2811-1-F3-A,G,SSOP-4,SMD | RENESAS TECHNOLOGY AMERICA INC | PS2811-1-F3-A | G | PWA BOM |  |
|  |  | NO | 330102900-289-G | OPTO-IC,ISOL,LTV-217-G,SSOP,4P,G | LITE-ON TECHNOLOGY CORPORATION | LTV-217-G | G | PWA BOM |  |
|  |  | ADD | 330103T00-029-G | IC,Optocoupler,VOS618A-3X001T,G,SSOP-4,SMD | VISHAY ENTER TECHNO LOGY.INC | VOS618A-3X001T | G | PWA BOM |  |
|  |  | Delete | VOS618A-3T | OPTO-IC,VOS618A-3T | VISHAY ENTER TECHNO LOGY.INC | VOS618A-3T | G | PWA BOM |  |
| 8 | Y1,Y2 |  | 71020KL00-100-G | OSC,33MHz,+/-50ppm,3.3V,15pF,G,SMD | TXC CORPORATION | 7X33000013 | G | PWA BOM |  |
|  |  | ADD | 710211800-967-G | OSC,33MHz,+/-50ppm,3.3V,15pF,G,SMD | eCERA | FK3300011 | G | PWA BOM |  |
|  |  | ADD | 710216N00-873-G | OSC,33MHz,+/-50ppm,3.3V,15pF,G,SMD | Kyocera | KC3225K33.0000C10E00 | G | PWA BOM |  |
| OOOOOOOOOOOOOOOOOOOOOOOOOOOOOOOOOOOOOOOOOOOOOOOOOOOOOOOOOOOOOOOOOOOOOOOOOOOOOOOOOOOOOOOOOO | OOOOOOOOOOOOOOOOOOOOOOOOOOOOOOOOOOOOOOOOOOOOOOOOOOOOOOOOOOOOOOOOOOOOOOOOOOOOOOOOOOOOOOOOOO | OOOOOOOOOOOOOOOOOOOOOOOOOOOOOOOOOOOOOOOOOOOOOOOOOOOOOOOOOOOOOOOOOOOOOOOOOOOOOOOOOOOOOOOOOO | OOOOOOOOOOOOOOOOOOOOOOOOOOOOOOOOOOOOOOOOOOOOOOOOOOOOOOOOOOOOOOOOOOOOOOOOOOOOOOOOOOOOOOOOOO | OOOOOOOOOOOOOOOOOOOOOOOOOOOOOOOOOOOOOOOOOOOOOOOOOOOOOOOOOOOOOOOOOOOOOOOOOOOOOOOOOOOOOOOOOO | OOOOOOOOOOOOOOOOOOOOOOOOOOOOOOOOOOOOOOOOOOOOOOOOOOOOOOOOOOOOOOOOOOOOOOOOOOOOOOOOOOOOOOOOOO | OOOOOOOOOOOOOOOOOOOOOOOOOOOOOOOOOOOOOOOOOOOOOOOOOOOOOOOOOOOOOOOOOOOOOOOOOOOOOOOOOOOOOOOOOO | OOOOOOOOOOOOOOOOOOOOOOOOOOOOOOOOOOOOOOOOOOOOOOOOOOOOOOOOOOOOOOOOOOOOOOOOOOOOOOOOOOOOOOOOOO | OOOOOOOOOOOOOOOOOOOOOOOOOOOOOOOOOOOOOOOOOOOOOOOOOOOOOOOOOOOOOOOOOOOOOOOOOOOOOOOOOOOOOOOOOO | OOOOOOOOOOOOOOOOOOOOOOOOOOOOOOOOOOOOOOOOOOOOOOOOOOOOOOOOOOOOOOOOOOOOOOOOOOOOOOOOOOOOOOOOOO |
| Master Materials Change |  |  |  |  |  |  |  |  |  |
| Item | Foxconn P/N | Orig._Usage | New_Usage | Part Description | Manufacturer Full Name | Manufacturer P/N | RoHS | Location | Sheet |
| 1 | PCB | 0 | 1 | PCB | PCB | PCB | G | (+)PCB | PWA BOM |
| 2 | 620101T02-015-G | 17 | 19 | CAP,100nF,+/-10%,X7R,16V,G,SMD0402 | MURATA ELEC. NORTH AMERICA | GRM155R71C104K | G | (+)C71,C72 | PWA BOM |
|  | 620101T00-012-G |  |  | CAP,100nF,+/-10%,X7R,16V,G,SMD0402 | WALSIN TECHNOLOGY CORPORATION | 0402B104K160CT |  |  | PWA BOM |
|  | 620101T00-026-G |  |  | CAP,100nF,+/-10%,X7R,16V,G,SMD0402 | SAMSUNG SEMICONDUCTOR | CL05B104KO5NNNC |  |  | PWA BOM |
|  | 620101T00-015-G |  |  | CAP,100nF,+/-10%,X7R,16V,G,SMD0402 | MURATA ELEC. NORTH AMERICA | GRM155R71C104KA88D |  |  | PWA BOM |
| 3 | 0438005.WRGT | 0 | 6 | Fuse,Fast acting,32V,5A,G,SMD0603 | LITTELFUSE FAR EAST PTE LTD | 0438005.WRGT | G | (+)FS4,FS5,FS6,FS7,FS8,FS9 | PWA BOM |
|  | 730103M00-086-G |  |  | Fuse,Fast acting,32V,5A,G,SMD0603 | LITTELFUSE FAR EAST PTE LTD | 0438005.WR |  |  | PWA BOM |
|  | 730103M00-088-G |  |  | Fuse,Fast acting,32V,5A,SMD0603,G | COOPER BUSSMANN, INC. | CC06H5A-TR |  |  | PWA BOM |
| 4 | 22-23-2081 | 0 | 6 | CONN,Header,WTB,1X8,V/T,Bla,2.54mm,G,DIP-8 | MOLEX INCORPORATED | 22-23-2081 | G | (+)J4,J5,J6,J7,J8,J9 | PWA BOM |
| 5 | 52113DU00-289-G | 0 | 2 | LED,Hyper Red,LTS-2307CKD-P,G,5V,25mA,G,SMD-10 | LITE-ON TECHNOLOGY CORPORATION | LTS-2307CKD-P | G | (+)LED1,LED2 | PWA BOM |
| 6 | 610119C00-017-G | 1 | 2 | RES,130KOhm,+/-1%,1/16W,G,SMD0402 | KOA SPEER ELECTRONICS, INC. | RK73H1ETTP1303F | G | (+)  PSUR2 | PWA BOM |
|  | 610119C00-011-G |  |  | RES,130KOhm,+/-1%,1/16W,G,SMD0402 | YAGEO CORPORATION COMPONENT | RC0402FR-07130KL |  |  | PWA BOM |
|  | 610119C00-012-G |  |  | RES,130KOhm,+/-1%,1/16W,G,SMD0402 | WALSIN TECHNOLOGY CORPORATION | WR04X1303FTL |  |  | PWA BOM |
|  | 610119C00-044-G |  |  | RES,130KOhm,+/-1%,1/16W,G,SMD0402 | TA-I TECHNOLOGY CO., LTD | RM04FTN1303 |  |  | PWA BOM |
| 7 | 610107A00-017-G | 65 | 64 | RES,0 Ohm,+/-5%,1/16W,G,SMD0402 | KOA SPEER ELECTRONICS, INC. | RK73Z1ETTP | G | (-)PHAR33 | PWA BOM |
|  | 610107A00-012-G |  |  | RES,0 Ohm,+/-5%,1/16W,G,SMD0402 | WALSIN TECHNOLOGY CORPORATION | WR04X000PTL |  |  | PWA BOM |
|  | 610107A00-011-G |  |  | RES,0 Ohm,+/-5%,1/16W,G,SMD0402 | YAGEO CORPORATION COMPONENT | RC0402JR-070RL |  |  | PWA BOM |
|  | 610107A00-044-G |  |  | RES,0 Ohm,+/-5%,1/16W,G,SMD0402 | TA-I TECHNOLOGY CO., LTD. | RM04JTN0 |  |  | PWA BOM |
|  | 610107A00-024-G |  |  | RES,0 Ohm,+/-5%,1/16W,G,SMD0402 | PANASONIC INDUSTRIAL CO.,LTD. | ERJ2GE0R00X |  |  | PWA BOM |
|  | 610107A00-029-G |  |  | RES,0 Ohm,+/-5%,1/16W,G,SMD0402 | VISHAY ENTER TECHNO LOGY.INC | CRCW04020000Z0ED |  |  | PWA BOM |
| 8 | 610601801-32D-G | 0 | 1 | RES,0.5mOhm,+/-1%,2W,G,SMD1225 | Thin Film Technology Corporation | CPA1225R0M50FW-T5 | G | (+)PHAR1 | PWA BOM |
| 9 | 61010L300-017-G | 1 | 2 | RES,1KOhm,+/-1%,1/16W,G,SMD0402 | KOA SPEER ELECTRONICS, INC. | RK73H1ETTP1001F | G | (+)R251 | PWA BOM |
|  | 61010L300-012-G |  |  | RES,1KOhm,+/-1%,1/16W,G,SMD0402 | WALSIN TECHNOLOGY CORPORATION | WR04X1001FTL |  |  | PWA BOM |
|  | 61010L300-011-G |  |  | RES,1KOhm,+/-1%,1/16W,G,SMD0402 | YAGEO CORPORATION COMPONENT | RC0402FR-071KL |  |  | PWA BOM |
|  | 61010L300-044-G |  |  | RES,1KOhm,+/-1%,1/16W,G,SMD0402 | TA-I TECHNOLOGY CO., LTD. | RM04FTN1001 |  |  | PWA BOM |
|  | 61010L300-024-G |  |  | RES,1KOhm,+/-1%,1/16W,G,SMD0402 | PANASONIC INDUSTRIAL CO.,LTD. | ERJ2RKF1001X |  |  | PWA BOM |
|  | 61010L300-029-G |  |  | RES,1KOhm,+/-1%,1/16W,G,SMD0402 | VISHAY ENTER TECHNO LOGY.INC | CRCW04021K00FKED |  |  | PWA BOM |
| 10 | 61010G500-017-G | 17 | 18 | RES,10KOhm,+/-1%,1/16W,G,SMD0402 | KOA SPEER ELECTRONICS, INC. | RK73H1ETTP1002F | G | (+)PEUR2 | PWA BOM |
|  | 61010G500-012-G |  |  | RES,10KOhm,+/-1%,1/16W,G,SMD0402 | WALSIN TECHNOLOGY CORPORATION | WR04X1002FTL |  |  | PWA BOM |
|  | 61010G500-011-G |  |  | RES,10KOhm,+/-1%,1/16W,G,SMD0402 | YAGEO CORPORATION COMPONENT | RC0402FR-0710KL |  |  | PWA BOM |
|  | 61010G500-044-G |  |  | RES,10KOhm,+/-1%,1/16W,G,SMD0402 | TA-I TECHNOLOGY CO., LTD. | RM04FTN1002 |  |  | PWA BOM |
|  | 61010G500-029-G |  |  | RES,10KOhm,+/-1%,1/16W,G,SMD0402 | VISHAY ENTER TECHNO LOGY.INC | CRCW040210K0FKED |  |  | PWA BOM |
|  | 61010G500-024-G |  |  | RES,10KOhm,+/-1%,1/16W,G,SMD0402 | PANASONIC INDUSTRIAL CO.,LTD. | ERJ2RKF1002X |  |  | PWA BOM |
| 11 | 61010JY00-017-G | 3 | 18 | RES,220 Ohm,+/-5%,1/16W,G,SMD0402 | KOA SPEER ELECTRONICS, INC. | RK73B1ETTP221J | G | (+)R252,R253,R254,R255,R256,R257,R258,R260,R261,R262,R263,R264,R265,R266,R267 | PWA BOM |
|  | 61010JY00-012-G |  |  | RES,220 Ohm,+/-5%,1/16W,G,SMD0402 | WALSIN TECHNOLOGY CORPORATION | WR04X221JTL |  |  | PWA BOM |
|  | 61010JY00-011-G |  |  | RES,220 Ohm,+/-5%,1/16W,G,SMD0402 | YAGEO CORPORATION COMPONENT | RC0402JR-07220RL |  |  | PWA BOM |
|  | 61010JY00-044-G |  |  | RES,220 Ohm,+/-5%,1/16W,G,SMD0402 | TA-I TECHNOLOGY CO., LTD. | RM04JTN221 |  |  | PWA BOM |
| 12 | 610107C00-017-G | 0 | 2 | RES,10KOhm,+/-5%,1/16W,G,SMD0402 | KOA SPEER ELECTRONICS, INC. | RK73B1ETTP103J | G | (+)R250,R259 | PWA BOM |
|  | 610107C00-012-G |  |  | RES,10KOhm,+/-5%,1/16W,G,SMD0402 | WALSIN TECHNOLOGY CORPORATION | WR04X103JTL |  |  | PWA BOM |
|  | 610107C00-011-G |  |  | RES,10KOhm,+/-5%,1/16W,G,SMD0402 | YAGEO CORPORATION COMPONENT | RC0402JR-0710KL |  |  | PWA BOM |
|  | 610107C00-044-G |  |  | RES,10KOhm,+/-5%,1/16W,G,SMD0402 | TA-I TECHNOLOGY CO., LTD | RM04JTN103 |  |  | PWA BOM |
|  | 610107C00-024-G |  |  | RES,10KOhm,+/-5%,1/16W,G,SMD0402 | PANASONIC INDUSTRIAL CO.,LTD. | ERJ2GEJ103X |  |  | PWA BOM |
|  | 610107C00-029-G |  |  | RES,10KOhm,+/-5%,1/16W,G,SMD0402 | VISHAY ENTER TECHNO LOGY.INC | CRCW040210K0JNED |  |  | PWA BOM |
| 13 | 41040J500-232-G | 0 | 1 | EEPROM,24AA024T-I/SN,1.7V~5.5V,2K,I2C,G,SOIC-8,SMD | MICROCHIP TECHNOLOGY INC | 24AA024T-I/SN | G | (+)U_FPDB_FRU | PWA BOM |
| 14 | 310200R00-183-G | 0 | 2 | IC,Trigger,SN74LV164ADBR,2~5.5V,G,SSOP-14,SMD | TEXAS INSTRUMENTS | SN74LV164ADBR | G | (+)U25,U26 | PWA BOM |
| 15 | 3406A1800-317-G | 0 | 1 | CONN,Header,WTB,1X8,V/T,Bla,2.54mm,G,DIP-8 | MOLEX INCORPORATED | 171856-0108 | G | (+)J1 | PWA BOM |
| 16 | 3406ARH00-309-G | 0 | 1 | CONN,Header,Socket,V/T,Bla,2.54mm,10u,G,DIP-8 | SAMTEC INC. | ESQ-104-33-L-D | G | (+)J10 | PWA BOM |
| 17 | 61011GD00-017-G | 0 | 1 | RES,15.4KOhm,+/-1%,1/16W,G,SMD0402 | KOA SPEER ELECTRONICS, INC. | RK73H1ETTP1542F | G | (+)PSUR1 | PWA BOM |
|  | 61011GD00-011-G |  |  | RES,15.4KOhm,+/-1%,1/16W,G,SMD0402 | YAGEO CORPORATION COMPONENT | RC0402FR-0715K4L |  |  | PWA BOM |
|  | 61011GD00-012-G |  |  | RES,15.4KOhm,+/-1%,1/16W,G,SMD0402 | WALSIN TECHNOLOGY CORPORATION | WR04X1542FTL |  |  | PWA BOM |
|  | 61011GD00-044-G |  |  | RES,15.4KOhm,+/-1%,1/16W,G,SMD0402 | TA-I TECHNOLOGY CO., LTD. | RM04FTN1542 |  |  | PWA BOM |
| 18 | 0101F1100-000-G | 1 | 0 | PCB,Zaius-FPDB DVT-X01,OSP,Blu,6L,18.2623*7.025,G | GOLD CIRCUIT ELECTRONICS LTD. | 0101F1100-000-G | G | (-)PCB | PWA BOM |
| 19 | 730103M00-086-G | 6 | 0 | Fuse,Fast acting,32V,5A,G,SMD0603 | LITTELFUSE FAR EAST PTE LTD | 0438005.WR | G | (-)FS4,FS5,FS6,FS7,FS8,FS9 | PWA BOM |
|  | 730103M00-088-G |  |  | Fuse,Fast acting,32V,5A,SMD0603,G | COOPER BUSSMANN, INC. | CC06H5A-TR |  |  | PWA BOM |
| 20 | 340699J00-317-G | 6 | 0 | CONN,Header,WTB,1X8,V/T,Bla,2.54mm,G,DIP-8 | MOLEX INCORPORATED | 22-23-2081 | G | (-)J4,J5,J6,J7,J8,J9 | PWA BOM |
| 21 | 610116G00-017-G | 3 | 0 | RES,150KOhm,+/-1%,1/16W,G,SMD0402 | KOA SPEER ELECTRONICS, INC. | RK73H1ETTP1503F | G | (-)PSUR2,PEUR2,PEUR7 | PWA BOM |
|  | 610116G00-011-G |  |  | RES,150KOhm,+/-1%,1/16W,G,SMD0402 | YAGEO CORPORATION COMPONENT | RC0402FR-07150KL |  |  | PWA BOM |
|  | 610116G00-012-G |  |  | RES,150KOhm,+/-1%,1/16W,G,SMD0402 | WALSIN TECHNOLOGY CORPORATION | WR04X1503FTL |  |  | PWA BOM |
|  | 610116G00-044-G |  |  | RES,150KOhm,+/-1%,1/16W,G,SMD0402 | TA-I TECHNOLOGY CO., LTD | RM04FTN1503 |  |  | PWA BOM |
| 22 | 610118S00-017-G | 2 | 0 | RES,54.9KOhm,+/-1%,1/16W,G,SMD0402 | KOA SPEER ELECTRONICS, INC. | RK73H1ETTP5492F | G | (-)PSUR4,PEUR6 | PWA BOM |
|  | 610118S00-011-G |  |  | RES,54.9KOhm,+/-1%,1/16W,G,SMD0402 | YAGEO CORPORATION COMPONENT | RC0402FR-0754K9L |  |  | PWA BOM |
|  | 610118S00-012-G |  |  | RES,54.9KOhm,+/-1%,1/16W,G,SMD0402 | WALSIN TECHNOLOGY CORPORATION | WR04X5492FTL |  |  | PWA BOM |
|  | 610118S00-044-G |  |  | RES,54.9KOhm,+/-1%,1/16W,G,SMD0402 | TA-I TECHNOLOGY CO., LTD. | RM04FTN5492 |  |  | PWA BOM |
| 23 | 610601800-32D-G | 1 | 0 | RES,0.5mOhm,+/-1%,2W,G,SMD1225 | Thin Film Technology Corporation | CPA1225R0M50FW-T5 | G | (-)PHAR1 | PWA BOM |
| 24 | 61011NY00-017-G | 1 | 0 | RES,88.7KOhm,+/-1%,1/16W,G,SMD0402 | KOA SPEER ELECTRONICS, INC. | RK73H1ETTP8872F | G | (-)PSUR1 | PWA BOM |
| 25 | 61011N000-017-G | 1 | 0 | RES,68KOhm,+/-1%,1/16W,G,SMD0402 | KOA SPEER ELECTRONICS, INC. | RK73H1ETTP6802F | G | (-)PSUR5 | PWA BOM |
| 26 | 41040HW00-191-G | 1 | 0 | EEPROM,AT24C02D-SSHM-T,1.7~3.6V,2K,I2C,G,SOIC-8,SMD | ATMEL CORPORATION | AT24C02D-SSHM-T | G | (-)U_FPDB_FRU | PWA BOM |
|  | 410401W00-214-G |  |  | EEPROM,M24C02-WMN6TP,2.5~5.5V,256*8,I2C,G,SOIC-8,SMD | ST MICRO ELECTRONICS,INC | M24C02-WMN6TP |  |  | PWA BOM |
|  | 41040CW00-232-G |  |  | EEPROM,24AA024-I/SN,1.7~5.5V,2K,I2C,G,SOIC-8,SMD | MICROCHIP TECHNOLOGY INC | 24AA024-I/SN |  |  | PWA BOM |
| 27 | 3406ANQ00-317-G | 1 | 0 | CONN,Header,Power,V/T,Bla,10mm,30u,G,DIP-8 | MOLEX INCORPORATED | 42819-4213 | G | (-)J1 | PWA BOM |
| 28 | 34080F500-653-G | 2 | 0 | CONN,Switch,slide,25mA,24V,G,SMD-8 | DIPTRONICS MANUFACTURING INC. | DHN-04F-T-V-T/R | G | (-)PSUSW1,PEUSW1 | PWA BOM |
| OOOOOOOOOOOOOOOOOOOOOOOOOOOOOOOOOOOOOOOOOOOOOOOOOOOOOOOOOOOOOOOOOOOOOOOOOOOOOOOOOOOOOOOOOO | OOOOOOOOOOOOOOOOOOOOOOOOOOOOOOOOOOOOOOOOOOOOOOOOOOOOOOOOOOOOOOOOOOOOOOOOOOOOOOOOOOOOOOOOOO | OOOOOOOOOOOOOOOOOOOOOOOOOOOOOOOOOOOOOOOOOOOOOOOOOOOOOOOOOOOOOOOOOOOOOOOOOOOOOOOOOOOOOOOOOO | OOOOOOOOOOOOOOOOOOOOOOOOOOOOOOOOOOOOOOOOOOOOOOOOOOOOOOOOOOOOOOOOOOOOOOOOOOOOOOOOOOOOOOOOOO | OOOOOOOOOOOOOOOOOOOOOOOOOOOOOOOOOOOOOOOOOOOOOOOOOOOOOOOOOOOOOOOOOOOOOOOOOOOOOOOOOOOOOOOOOO | OOOOOOOOOOOOOOOOOOOOOOOOOOOOOOOOOOOOOOOOOOOOOOOOOOOOOOOOOOOOOOOOOOOOOOOOOOOOOOOOOOOOOOOOOO | OOOOOOOOOOOOOOOOOOOOOOOOOOOOOOOOOOOOOOOOOOOOOOOOOOOOOOOOOOOOOOOOOOOOOOOOOOOOOOOOOOOOOOOOOO | OOOOOOOOOOOOOOOOOOOOOOOOOOOOOOOOOOOOOOOOOOOOOOOOOOOOOOOOOOOOOOOOOOOOOOOOOOOOOOOOOOOOOOOOOO | OOOOOOOOOOOOOOOOOOOOOOOOOOOOOOOOOOOOOOOOOOOOOOOOOOOOOOOOOOOOOOOOOOOOOOOOOOOOOOOOOOOOOOOOOO | OOOOOOOOOOOOOOOOOOOOOOOOOOOOOOOOOOOOOOOOOOOOOOOOOOOOOOOOOOOOOOOOOOOOOOOOOOOOOOOOOOOOOOOOOO |
| TLA Parts Change |  |  |  |  |  |  |  |  |  |
| Item | Foxconn P/N | Qty | Part Description | Manufacturer Full Name | Manufacturer P/N | RoHS | Location | Remark | BOM |
| BOM Change List Date:Thu Sep 07 15:27:08 CST 2017 |  |  |  |  |  |  |  |  |  |
| New BOM file : E:\barreleye g2\0905\foxbis\BARRELEYE_G2-FPDB_POST-PVT-X01-BOM-X04-20170907.xls |  |  |  |  |  |  |  |  |  |
| Old BOM file : E:\barreleye g2\0905\foxbis\BG2 0906.xls |  |  |  |  |  |  |  |  |  |
| ##### Add Parts |  |  |  |  |  |  |  |  |  |
| Item | Location | Qty | Foxconn P/N | Part Description | Manufacturer Full Name | Manufacturer P/N | RoHS | Sheet |  |
| 1 | PSUR2,PEUR7 | 2 | 610116G00-017-G | RES,150KOhm,+/-1%,1/16W,G,SMD0402 | KOA SPEER ELECTRONICS, INC. | RK73H1ETTP1503F | G | PWA BOM |  |
|  |  |  | 610116G00-011-G | RES,150KOhm,+/-1%,1/16W,G,SMD0402 | YAGEO CORPORATION COMPONENT | RC0402FR-07150KL | G | PWA BOM |  |
|  |  |  | 610116G00-044-G | RES,150KOhm,+/-1%,1/16W,G,SMD0402 | TA-I TECHNOLOGY CO., LTD | RM04FTN1503 | G | PWA BOM |  |
|  |  |  | 610116G00-012-G | RES,150KOhm,+/-1%,1/16W,G,SMD0402 | WALSIN TECHNOLOGY CORPORATION | WR04X1503FTL | G | PWA BOM |  |
| 2 | PSUR4,PEUR6 | 2 | 610118S00-017-G | RES,54.9KOhm,+/-1%,1/16W,G,SMD0402 | KOA SPEER ELECTRONICS, INC. | RK73H1ETTP5492F | G | PWA BOM |  |
|  |  |  | 610118S00-011-G | RES,54.9KOhm,+/-1%,1/16W,G,SMD0402 | YAGEO CORPORATION COMPONENT | RC0402FR-0754K9L |  | PWA BOM |  |
|  |  |  | 610118S00-044-G | RES,54.9KOhm,+/-1%,1/16W,G,SMD0402 | TA-I TECHNOLOGY CO., LTD | RM04FTN5492 |  | PWA BOM |  |
|  |  |  | 610118S00-012-G | RES,54.9KOhm,+/-1%,1/16W,G,SMD0402 | WALSIN TECHNOLOGY CORPORATION | WR04X5492FTL |  | PWA BOM |  |
| 3 | PSUR5 | 1 | 61011N000-017-G | RES,68KOhm,+/-1%,1/16W,G,SMD0402 | KOA SPEER ELECTRONICS, INC. | RK73H1ETTP6802F | G | PWA BOM |  |
|  |  |  | 61011N000-011-G | RES,68KOhm,+/-1%,1/16W,G,SMD0402 | YAGEO CORPORATION COMPONENT | RC0402FR-0768KL | G | PWA BOM |  |
|  |  |  | 61011N000-044-G | RES,68KOhm,+/-1%,1/16W,G,SMD0402 | TA-I TECHNOLOGY CO., LTD. | RM04FTN6802 | G | PWA BOM |  |
|  |  |  | 61011N000-012-G | RES,68KOhm,+/-1%,1/16W,G,SMD0402 | WALSIN TECHNOLOGY CORPORATION | WR04X6802FTL | G | PWA BOM |  |
| ##### Remove Parts |  |  |  |  |  |  |  |  |  |
| Item | Location | Qty | Foxconn P/N | Part Description | Manufacturer Full Name | Manufacturer P/N | RoHS | Sheet |  |
| 1 | PSUR2 | 1 | 610119C00-017-G | RES,130KOhm,+/-1%,1/16W,G,SMD0402 | KOA SPEER ELECTRONICS, INC. | RK73H1ETTP1303F | G | PWA BOM |  |
|  |  |  | 610119C00-011-G | RES,130KOhm,+/-1%,1/16W,G,SMD0402 | YAGEO CORPORATION COMPONENT | RC0402FR-07130KL | G | PWA BOM |  |
|  |  |  | 610119C00-012-G | RES,130KOhm,+/-1%,1/16W,G,SMD0402 | WALSIN TECHNOLOGY CORPORATION | WR04X1303FTL | G | PWA BOM |  |
|  |  |  | 610119C00-044-G | RES,130KOhm,+/-1%,1/16W,G,SMD0402 | TA-I TECHNOLOGY CO., LTD | RM04FTN1303 | G | PWA BOM |  |
| ##### Change Parts |  |  |  |  |  |  |  |  |  |
| Item | Location | Qty | Foxconn P/N | Part Description | Manufacturer Full Name | Manufacturer P/N | RoHS | Sheet | Remark |
| 1 | PHAC3 | 1 | 620133600-015-G | CAP,1nF,+/-5%,X7R,100V,G,SMD0805 | MURATA ELEC. NORTH AMERICA | GRM219R72A102JA01D | G | PWA BOM | In New BOM |
|  |  |  | 620133600-012-G | CAP,1nF,+/-5%,X7R,100V,G,SMD0805 | WALSIN TECHNOLOGY CORPORATION | 0805B102J101CT | G | PWA BOM | In New BOM |
|  |  |  | 620133600-026-G | CAP,1nF,+/-5%,X7R,100V,G,SMD0805 | SAMSUNG SEMICONDUCTOR | CL21B102JCANNNC | G | PWA BOM | In New BOM |
|  | PHAC3 | 1 | 620133600-015-G | CAP,1nF,+/-5%,X7R,100V,G,SMD0805 | MURATA ELEC. NORTH AMERICA | GRM219R72A102JA01D | G | PWA BOM | In Old BOM |
|  |  |  | 620133600-012-G | CAP,1nF,+/-5%,X7R,100V,G,SMD0805 | WALSIN TECHNOLOGY CORPORATION | 0805B102J101CT | G | PWA BOM | In Old BOM |
|  |  |  | 620133600-026-G | CAP,1nF,+/-5%,X7R,100V,G,SMD0805 | SAMSUNG SEMICONDUCTOR | CL21B102JCANNNC |  | PWA BOM | In Old BOM |
| 2 | R1483 | 1 | 61100QT01-017-G | RES,10 Ohm,+/-0.5%,1/16W,G,SMD0402 | KOA SPEER ELECTRONICS, INC. | RN731ETTP10R0D25 | G | PWA BOM | In New BOM |
|  |  |  | 61100QT00-011-G | RES,10 Ohm,+/-0.5%,1/16W,G,SMD0402 | YAGEO CORPORATION COMPONENT | RT0402DRE0710RL | G | PWA BOM | In New BOM |
|  |  |  | 61100QT00-012-G | RES,10 Ohm,+/-0.5%,1/16W,G,SMD0402 | WALSIN TECHNOLOGY CORPORATION | WF04T10R0DTL | G | PWA BOM | In New BOM |
|  | R1483 | 1 | 61100QT01-017-G | RES,10 Ohm,+/-0.5%,1/16W,G,SMD0402 | KOA SPEER ELECTRONICS, INC. | RN731ETTP10R0D25 | G | PWA BOM | In Old BOM |
| 3 | PCB | 1 | PCB | PCB | PCB | PCB | G | PWA BOM | In New BOM |
|  | PCB | 1 | 0101FGL00-000-G | PCB | PCB | 0101FGL00-000-G | G | PWA BOM | In Old BOM |
| 4 | FS4,FS5,FS6,FS7,FS8,FS9 | 6 | 730103M00-086-G | Fuse,Fast acting,32V,5A,G,SMD0603 | LITTELFUSE FAR EAST PTE LTD | 0438005.WR | G | PWA BOM | In New BOM |
|  | FS4,FS5,FS6,FS7,FS8,FS9 | 6 | 0438005.WRGT | Fuse,Fast acting,32V,5A,G,SMD0603 | LITTELFUSE FAR EAST PTE LTD | 0438005.WRGT | G | PWA BOM | In Old BOM |
|  |  |  | 730103M00-086-G | Fuse,Fast acting,32V,5A,G,SMD0603 | LITTELFUSE FAR EAST PTE LTD | 0438005.WR | G | PWA BOM | In Old BOM |
|  |  |  | 730103M00-088-G | Fuse,Fast acting,32V,5A,SMD0603,G | COOPER BUSSMANN, INC. | CC06H5A-TR | G | PWA BOM | In Old BOM |
| 5 | PEUR2 | 1 | 610116G00-017-G | RES,150KOhm,+/-1%,1/16W,G,SMD0402 | KOA SPEER ELECTRONICS, INC. | RK73H1ETTP1503F | G | PWA BOM | In New BOM |
|  |  |  | 610116G00-011-G | RES,150KOhm,+/-1%,1/16W,G,SMD0402 | YAGEO CORPORATION COMPONENT | RC0402FR-07150KL | G | PWA BOM | In New BOM |
|  |  |  | 610116G00-044-G | RES,150KOhm,+/-1%,1/16W,G,SMD0402 | TA-I TECHNOLOGY CO., LTD | RM04FTN1503 | G | PWA BOM | In New BOM |
|  |  |  | 610116G00-012-G | RES,150KOhm,+/-1%,1/16W,G,SMD0402 | WALSIN TECHNOLOGY CORPORATION | WR04X1503FTL | G | PWA BOM | In New BOM |
|  | PEUR2 | 1 | 61010G500-017-G | RES,10KOhm,+/-1%,1/16W,G,SMD0402 | KOA SPEER ELECTRONICS, INC. | RK73H1ETTP1002F | G | PWA BOM | In Old BOM |
|  |  |  | 61010G500-012-G | RES,10KOhm,+/-1%,1/16W,G,SMD0402 | WALSIN TECHNOLOGY CORPORATION | WR04X1002FTL | G | PWA BOM | In Old BOM |
|  |  |  | 61010G500-011-G | RES,10KOhm,+/-1%,1/16W,G,SMD0402 | YAGEO CORPORATION COMPONENT | RC0402FR-0710KL | G | PWA BOM | In Old BOM |
|  |  |  | 61010G500-044-G | RES,10KOhm,+/-1%,1/16W,G,SMD0402 | TA-I TECHNOLOGY CO., LTD. | RM04FTN1002 | G | PWA BOM | In Old BOM |
|  |  |  | 61010G500-029-G | RES,10KOhm,+/-1%,1/16W,G,SMD0402 | VISHAY ENTER TECHNO LOGY.INC | CRCW040210K0FKED | G | PWA BOM | In Old BOM |
|  |  |  | 61010G500-024-G | RES,10KOhm,+/-1%,1/16W,G,SMD0402 | PANASONIC INDUSTRIAL CO.,LTD. | ERJ2RKF1002X | G | PWA BOM | In Old BOM |
| 6 | PHAR1 | 1 | 610601800-32D-G | RES,0.5mOhm,+/-1%,2W,G,SMD1225 | Thin Film Technology Corporation | CPA1225R0M50FW-T50 | G | PWA BOM | In New BOM |
|  | PHAR1 | 1 | 610601801-32D-G | RES,0.5mOhm,+/-1%,2W,G,SMD1225 | Thin Film Technology Corporation | CPA1225R0M50FW-T5 | G | PWA BOM | In Old BOM |
| 7 | PSUQ1 | 1 | 51030CQ00-185-G | MOS N,2N7002,60V,115mA,7.5ohm@5V,G,SOT23-3,SMD | FAIRCHILD SEMICONDUCTOR CORP | 2N7002 | G | PWA BOM | In New BOM |
|  | PSUQ1 | 1 | 510301N00-223-G | MOS N,2N7002LT1G,60V,0.115A,7.5ohm@5V,G,SOT23-3,SMD | ON SEMICONDUCTOR CORP | 2N7002LT1G | G | PWA BOM | In Old BOM |
|  |  |  | 51030CQ00-185-G | MOS N,2N7002,60V,115mA,7.5ohm@5V,G,SOT23-3,SMD | FAIRCHILD SEMICONDUCTOR CORP | 2N7002 | G | PWA BOM | In Old BOM |
| 8 | PSUR1 | 1 | 61011NY00-017-G | RES,88.7KOhm,+/-1%,1/16W,G,SMD0402 | KOA SPEER ELECTRONICS, INC. | RK73H1ETTP8872F | G | PWA BOM | In New BOM |
|  |  |  | 61011NY00-011-G | RES,88.7KOhm,+/-1%,1/16W,G,SMD0402 | YAGEO CORPORATION COMPONENT | RC0402FR-0788K7L | G | PWA BOM | In New BOM |
|  |  |  | 61011NY00-012-G | RES,88.7KOhm,+/-1%,1/16W,G,SMD0402 | WALSIN TECHNOLOGY CORPORATION | WR04X8872FTL | G | PWA BOM | In New BOM |
|  | PSUR1 | 1 | 61011GD00-017-G | RES,15.4KOhm,+/-1%,1/16W,G,SMD0402 | KOA SPEER ELECTRONICS, INC. | RK73H1ETTP1542F | G | PWA BOM | In Old BOM |
|  |  |  | 61011GD00-011-G | RES,15.4KOhm,+/-1%,1/16W,G,SMD0402 | YAGEO CORPORATION COMPONENT | RC0402FR-0715K4L | G | PWA BOM | In Old BOM |
|  |  |  | 61011GD00-012-G | RES,15.4KOhm,+/-1%,1/16W,G,SMD0402 | WALSIN TECHNOLOGY CORPORATION | WR04X1542FTL | G | PWA BOM | In Old BOM |
|  |  |  | 61011GD00-044-G | RES,15.4KOhm,+/-1%,1/16W,G,SMD0402 | TA-I TECHNOLOGY CO., LTD. | RM04FTN1542 | G | PWA BOM | In Old BOM |
| 9 | U_FPDB_FRU | 1 | 41040HW00-191-G | EEPROM,AT24C02D-SSHM-T,1.7~3.6V,2K,I2C,G,SOIC-8,SMD | ATMEL CORPORATION | 24AA024T-I/SN | G | PWA BOM | In New BOM |
|  | U_FPDB_FRU | 1 | 41040J500-232-G | EEPROM,24AA024T-I/SN,1.7V~5.5V,2K,I2C,G,SOIC-8,SMD | MICROCHIP TECHNOLOGY INC | 24AA024T-I/SN | G | PWA BOM | In Old BOM |
| ##### Change Revision |  |  |  |  |  |  |  |  |  |
| Sheet | REV OF BOM | CUSTOMER | CUSTOMER P/N | PWA PN | PWA DESCRIPTION | PWA REV | DATE | Remark |  |
| PWA BOM | X04 | Customer |  |  |  | X01 | 9/7/17 | In New BOM |  |
| PWA BOM |  | Customer |  |  |  |  |  | In Old BOM |  |
| OOOOOOOOOOOOOOOOOOOOOOOOOOOOOOOOOOOOOOOOOOOOOOOOOOOOOOOOOOOOOOOOOOOOOOOOOOOOOOOOOOOOOOOOOO | OOOOOOOOOOOOOOOOOOOOOOOOOOOOOOOOOOOOOOOOOOOOOOOOOOOOOOOOOOOOOOOOOOOOOOOOOOOOOOOOOOOOOOOOOO | OOOOOOOOOOOOOOOOOOOOOOOOOOOOOOOOOOOOOOOOOOOOOOOOOOOOOOOOOOOOOOOOOOOOOOOOOOOOOOOOOOOOOOOOOO | OOOOOOOOOOOOOOOOOOOOOOOOOOOOOOOOOOOOOOOOOOOOOOOOOOOOOOOOOOOOOOOOOOOOOOOOOOOOOOOOOOOOOOOOOO | OOOOOOOOOOOOOOOOOOOOOOOOOOOOOOOOOOOOOOOOOOOOOOOOOOOOOOOOOOOOOOOOOOOOOOOOOOOOOOOOOOOOOOOOOO | OOOOOOOOOOOOOOOOOOOOOOOOOOOOOOOOOOOOOOOOOOOOOOOOOOOOOOOOOOOOOOOOOOOOOOOOOOOOOOOOOOOOOOOOOO | OOOOOOOOOOOOOOOOOOOOOOOOOOOOOOOOOOOOOOOOOOOOOOOOOOOOOOOOOOOOOOOOOOOOOOOOOOOOOOOOOOOOOOOOOO | OOOOOOOOOOOOOOOOOOOOOOOOOOOOOOOOOOOOOOOOOOOOOOOOOOOOOOOOOOOOOOOOOOOOOOOOOOOOOOOOOOOOOOOOOO | OOOOOOOOOOOOOOOOOOOOOOOOOOOOOOOOOOOOOOOOOOOOOOOOOOOOOOOOOOOOOOOOOOOOOOOOOOOOOOOOOOOOOOOOOO | OOOOOOOOOOOOOOOOOOOOOOOOOOOOOOOOOOOOOOOOOOOOOOOOOOOOOOOOOOOOOOOOOOOOOOOOOOOOOOOOOOOOOOOOOO |
| Second Source Change |  |  |  |  |  |  |  |  |  |
| Item | Location | Change Type | Foxconn P/N | Part Description | Manufacturer Full Name | Manufacturer P/N | RoHS | Sheet |  |
| 1 | R1483 |  | 61100QT01-017-G | RES,10 Ohm,+/-0.5%,1/16W,G,SMD0402 | KOA SPEER ELECTRONICS, INC. | RN731ETTP10R0D25 | G | PWA BOM |  |
|  |  | ADD | 61100QT00-011-G | RES,10 Ohm,+/-0.5%,1/16W,G,SMD0402 | YAGEO CORPORATION COMPONENT | RT0402DRE0710RL | G | PWA BOM |  |
|  |  | ADD | 61100QT00-012-G | RES,10 Ohm,+/-0.5%,1/16W,G,SMD0402 | WALSIN TECHNOLOGY CORPORATION | WF04T10R0DTL | G | PWA BOM |  |
| OOOOOOOOOOOOOOOOOOOOOOOOOOOOOOOOOOOOOOOOOOOOOOOOOOOOOOOOOOOOOOOOOOOOOOOOOOOOOOOOOOOOOOOOOO | OOOOOOOOOOOOOOOOOOOOOOOOOOOOOOOOOOOOOOOOOOOOOOOOOOOOOOOOOOOOOOOOOOOOOOOOOOOOOOOOOOOOOOOOOO | OOOOOOOOOOOOOOOOOOOOOOOOOOOOOOOOOOOOOOOOOOOOOOOOOOOOOOOOOOOOOOOOOOOOOOOOOOOOOOOOOOOOOOOOOO | OOOOOOOOOOOOOOOOOOOOOOOOOOOOOOOOOOOOOOOOOOOOOOOOOOOOOOOOOOOOOOOOOOOOOOOOOOOOOOOOOOOOOOOOOO | OOOOOOOOOOOOOOOOOOOOOOOOOOOOOOOOOOOOOOOOOOOOOOOOOOOOOOOOOOOOOOOOOOOOOOOOOOOOOOOOOOOOOOOOOO | OOOOOOOOOOOOOOOOOOOOOOOOOOOOOOOOOOOOOOOOOOOOOOOOOOOOOOOOOOOOOOOOOOOOOOOOOOOOOOOOOOOOOOOOOO | OOOOOOOOOOOOOOOOOOOOOOOOOOOOOOOOOOOOOOOOOOOOOOOOOOOOOOOOOOOOOOOOOOOOOOOOOOOOOOOOOOOOOOOOOO | OOOOOOOOOOOOOOOOOOOOOOOOOOOOOOOOOOOOOOOOOOOOOOOOOOOOOOOOOOOOOOOOOOOOOOOOOOOOOOOOOOOOOOOOOO | OOOOOOOOOOOOOOOOOOOOOOOOOOOOOOOOOOOOOOOOOOOOOOOOOOOOOOOOOOOOOOOOOOOOOOOOOOOOOOOOOOOOOOOOOO | OOOOOOOOOOOOOOOOOOOOOOOOOOOOOOOOOOOOOOOOOOOOOOOOOOOOOOOOOOOOOOOOOOOOOOOOOOOOOOOOOOOOOOOOOO |
| Master Materials Change |  |  |  |  |  |  |  |  |  |
| Item | Foxconn P/N | Orig._Usage | New_Usage | Part Description | Manufacturer Full Name | Manufacturer P/N | RoHS | Location | Sheet |
| 1 | PCB | 0 | 1 | PCB | PCB | PCB | G | (+)PCB | PWA BOM |
| 2 | 730103M00-086-G | 0 | 6 | Fuse,Fast acting,32V,5A,G,SMD0603 | LITTELFUSE FAR EAST PTE LTD | 0438005.WR | G | (+)FS4,FS5,FS6,FS7,FS8,FS9 | PWA BOM |
| 3 | 610119C00-017-G | 2 | 1 | RES,130KOhm,+/-1%,1/16W,G,SMD0402 | KOA SPEER ELECTRONICS, INC. | RK73H1ETTP1303F | G | (-)  PSUR2 | PWA BOM |
|  | 610119C00-011-G |  |  | RES,130KOhm,+/-1%,1/16W,G,SMD0402 | YAGEO CORPORATION COMPONENT | RC0402FR-07130KL |  |  | PWA BOM |
|  | 610119C00-012-G |  |  | RES,130KOhm,+/-1%,1/16W,G,SMD0402 | WALSIN TECHNOLOGY CORPORATION | WR04X1303FTL |  |  | PWA BOM |
|  | 610119C00-044-G |  |  | RES,130KOhm,+/-1%,1/16W,G,SMD0402 | TA-I TECHNOLOGY CO., LTD | RM04FTN1303 |  |  | PWA BOM |
| 4 | 610116G00-017-G | 0 | 3 | RES,150KOhm,+/-1%,1/16W,G,SMD0402 | KOA SPEER ELECTRONICS, INC. | RK73H1ETTP1503F | G | (+)PSUR2,PEUR2,PEUR7 | PWA BOM |
|  | 610116G00-011-G |  |  | RES,150KOhm,+/-1%,1/16W,G,SMD0402 | YAGEO CORPORATION COMPONENT | RC0402FR-07150KL |  |  | PWA BOM |
|  | 610116G00-044-G |  |  | RES,150KOhm,+/-1%,1/16W,G,SMD0402 | TA-I TECHNOLOGY CO., LTD | RM04FTN1503 |  |  | PWA BOM |
|  | 610116G00-012-G |  |  | RES,150KOhm,+/-1%,1/16W,G,SMD0402 | WALSIN TECHNOLOGY CORPORATION | WR04X1503FTL |  |  | PWA BOM |
| 5 | 610118S00-017-G | 0 | 2 | RES,54.9KOhm,+/-1%,1/16W,G,SMD0402 | KOA SPEER ELECTRONICS, INC. | RK73H1ETTP5492F | G | (+)PSUR4,PEUR6 | PWA BOM |
|  | 610118S00-011-G |  |  | RES,54.9KOhm,+/-1%,1/16W,G,SMD0402 | YAGEO CORPORATION COMPONENT | RC0402FR-0754K9L |  |  | PWA BOM |
|  | 610118S00-044-G |  |  | RES,54.9KOhm,+/-1%,1/16W,G,SMD0402 | TA-I TECHNOLOGY CO., LTD | RM04FTN5492 |  |  | PWA BOM |
|  | 610118S00-012-G |  |  | RES,54.9KOhm,+/-1%,1/16W,G,SMD0402 | WALSIN TECHNOLOGY CORPORATION | WR04X5492FTL |  |  | PWA BOM |
| 6 | 610601800-32D-G | 0 | 1 | RES,0.5mOhm,+/-1%,2W,G,SMD1225 | Thin Film Technology Corporation | CPA1225R0M50FW-T50 | G | (+)PHAR1 | PWA BOM |
| 7 | 61010G500-017-G | 18 | 17 | RES,10KOhm,+/-1%,1/16W,G,SMD0402 | KOA SPEER ELECTRONICS, INC. | RK73H1ETTP1002F | G | (-)PEUR2 | PWA BOM |
|  | 61010G500-012-G |  |  | RES,10KOhm,+/-1%,1/16W,G,SMD0402 | WALSIN TECHNOLOGY CORPORATION | WR04X1002FTL |  |  | PWA BOM |
|  | 61010G500-011-G |  |  | RES,10KOhm,+/-1%,1/16W,G,SMD0402 | YAGEO CORPORATION COMPONENT | RC0402FR-0710KL |  |  | PWA BOM |
|  | 61010G500-044-G |  |  | RES,10KOhm,+/-1%,1/16W,G,SMD0402 | TA-I TECHNOLOGY CO., LTD. | RM04FTN1002 |  |  | PWA BOM |
|  | 61010G500-029-G |  |  | RES,10KOhm,+/-1%,1/16W,G,SMD0402 | VISHAY ENTER TECHNO LOGY.INC | CRCW040210K0FKED |  |  | PWA BOM |
|  | 61010G500-024-G |  |  | RES,10KOhm,+/-1%,1/16W,G,SMD0402 | PANASONIC INDUSTRIAL CO.,LTD. | ERJ2RKF1002X |  |  | PWA BOM |
| 8 | 51030CQ00-185-G | 0 | 1 | MOS N,2N7002,60V,115mA,7.5ohm@5V,G,SOT23-3,SMD | FAIRCHILD SEMICONDUCTOR CORP | 2N7002 | G | (+)PSUQ1 | PWA BOM |
| 9 | 61011NY00-017-G | 0 | 1 | RES,88.7KOhm,+/-1%,1/16W,G,SMD0402 | KOA SPEER ELECTRONICS, INC. | RK73H1ETTP8872F | G | (+)PSUR1 | PWA BOM |
|  | 61011NY00-011-G |  |  | RES,88.7KOhm,+/-1%,1/16W,G,SMD0402 | YAGEO CORPORATION COMPONENT | RC0402FR-0788K7L |  |  | PWA BOM |
|  | 61011NY00-012-G |  |  | RES,88.7KOhm,+/-1%,1/16W,G,SMD0402 | WALSIN TECHNOLOGY CORPORATION | WR04X8872FTL |  |  | PWA BOM |
| 10 | 61011N000-017-G | 0 | 1 | RES,68KOhm,+/-1%,1/16W,G,SMD0402 | KOA SPEER ELECTRONICS, INC. | RK73H1ETTP6802F | G | (+)PSUR5 | PWA BOM |
|  | 61011N000-011-G |  |  | RES,68KOhm,+/-1%,1/16W,G,SMD0402 | YAGEO CORPORATION COMPONENT | RC0402FR-0768KL |  |  | PWA BOM |
|  | 61011N000-044-G |  |  | RES,68KOhm,+/-1%,1/16W,G,SMD0402 | TA-I TECHNOLOGY CO., LTD. | RM04FTN6802 |  |  | PWA BOM |
|  | 61011N000-012-G |  |  | RES,68KOhm,+/-1%,1/16W,G,SMD0402 | WALSIN TECHNOLOGY CORPORATION | WR04X6802FTL |  |  | PWA BOM |
| 11 | 41040HW00-191-G | 0 | 1 | EEPROM,AT24C02D-SSHM-T,1.7~3.6V,2K,I2C,G,SOIC-8,SMD | ATMEL CORPORATION | 24AA024T-I/SN | G | (+)U_FPDB_FRU | PWA BOM |
| 12 | 0101FGL00-000-G | 1 | 0 | PCB | PCB | 0101FGL00-000-G | G | (-)PCB | PWA BOM |
| 13 | 0438005.WRGT | 6 | 0 | Fuse,Fast acting,32V,5A,G,SMD0603 | LITTELFUSE FAR EAST PTE LTD | 0438005.WRGT | G | (-)FS4,FS5,FS6,FS7,FS8,FS9 | PWA BOM |
|  | 730103M00-086-G |  |  | Fuse,Fast acting,32V,5A,G,SMD0603 | LITTELFUSE FAR EAST PTE LTD | 0438005.WR |  |  | PWA BOM |
|  | 730103M00-088-G |  |  | Fuse,Fast acting,32V,5A,SMD0603,G | COOPER BUSSMANN, INC. | CC06H5A-TR |  |  | PWA BOM |
| 14 | 610601801-32D-G | 1 | 0 | RES,0.5mOhm,+/-1%,2W,G,SMD1225 | Thin Film Technology Corporation | CPA1225R0M50FW-T5 | G | (-)PHAR1 | PWA BOM |
| 15 | 510301N00-223-G | 1 | 0 | MOS N,2N7002LT1G,60V,0.115A,7.5ohm@5V,G,SOT23-3,SMD | ON SEMICONDUCTOR CORP | 2N7002LT1G | G | (-)PSUQ1 | PWA BOM |
|  | 51030CQ00-185-G |  |  | MOS N,2N7002,60V,115mA,7.5ohm@5V,G,SOT23-3,SMD | FAIRCHILD SEMICONDUCTOR CORP | 2N7002 |  |  | PWA BOM |
| 16 | 41040J500-232-G | 1 | 0 | EEPROM,24AA024T-I/SN,1.7V~5.5V,2K,I2C,G,SOIC-8,SMD | MICROCHIP TECHNOLOGY INC | 24AA024T-I/SN | G | (-)U_FPDB_FRU | PWA BOM |
| 17 | 61011GD00-017-G | 1 | 0 | RES,15.4KOhm,+/-1%,1/16W,G,SMD0402 | KOA SPEER ELECTRONICS, INC. | RK73H1ETTP1542F | G | (-)PSUR1 | PWA BOM |
|  | 61011GD00-011-G |  |  | RES,15.4KOhm,+/-1%,1/16W,G,SMD0402 | YAGEO CORPORATION COMPONENT | RC0402FR-0715K4L |  |  | PWA BOM |
|  | 61011GD00-012-G |  |  | RES,15.4KOhm,+/-1%,1/16W,G,SMD0402 | WALSIN TECHNOLOGY CORPORATION | WR04X1542FTL |  |  | PWA BOM |
|  | 61011GD00-044-G |  |  | RES,15.4KOhm,+/-1%,1/16W,G,SMD0402 | TA-I TECHNOLOGY CO., LTD. | RM04FTN1542 |  |  | PWA BOM |
| OOOOOOOOOOOOOOOOOOOOOOOOOOOOOOOOOOOOOOOOOOOOOOOOOOOOOOOOOOOOOOOOOOOOOOOOOOOOOOOOOOOOOOOOOO | OOOOOOOOOOOOOOOOOOOOOOOOOOOOOOOOOOOOOOOOOOOOOOOOOOOOOOOOOOOOOOOOOOOOOOOOOOOOOOOOOOOOOOOOOO | OOOOOOOOOOOOOOOOOOOOOOOOOOOOOOOOOOOOOOOOOOOOOOOOOOOOOOOOOOOOOOOOOOOOOOOOOOOOOOOOOOOOOOOOOO | OOOOOOOOOOOOOOOOOOOOOOOOOOOOOOOOOOOOOOOOOOOOOOOOOOOOOOOOOOOOOOOOOOOOOOOOOOOOOOOOOOOOOOOOOO | OOOOOOOOOOOOOOOOOOOOOOOOOOOOOOOOOOOOOOOOOOOOOOOOOOOOOOOOOOOOOOOOOOOOOOOOOOOOOOOOOOOOOOOOOO | OOOOOOOOOOOOOOOOOOOOOOOOOOOOOOOOOOOOOOOOOOOOOOOOOOOOOOOOOOOOOOOOOOOOOOOOOOOOOOOOOOOOOOOOOO | OOOOOOOOOOOOOOOOOOOOOOOOOOOOOOOOOOOOOOOOOOOOOOOOOOOOOOOOOOOOOOOOOOOOOOOOOOOOOOOOOOOOOOOOOO | OOOOOOOOOOOOOOOOOOOOOOOOOOOOOOOOOOOOOOOOOOOOOOOOOOOOOOOOOOOOOOOOOOOOOOOOOOOOOOOOOOOOOOOOOO | OOOOOOOOOOOOOOOOOOOOOOOOOOOOOOOOOOOOOOOOOOOOOOOOOOOOOOOOOOOOOOOOOOOOOOOOOOOOOOOOOOOOOOOOOO | OOOOOOOOOOOOOOOOOOOOOOOOOOOOOOOOOOOOOOOOOOOOOOOOOOOOOOOOOOOOOOOOOOOOOOOOOOOOOOOOOOOOOOOOOO |
| TLA Parts Change |  |  |  |  |  |  |  |  |  |
| Item | Foxconn P/N | Qty | Part Description | Manufacturer Full Name | Manufacturer P/N | RoHS | Location | Remark | BOM |
| 1. Connector J1 change to 171856-0108 |  |  |  |  |  |  |  |  |  |
| 2.U_FPDB_FRU change to  24AA024T-I/SN |  |  |  |  |  |  |  |  |  |
| 3. POSTCARD POP |  |  |  |  |  |  |  |  |  |
| BOM Change List Date:Mon Sep 11 16:41:27 CST 2017 |  |  |  |  |  |  |  |  |  |
| New BOM file : E:\barreleye g2\0908\BARRELEYE_G2-FPDB_POST-PVT-X03-BOM-X04-20170908.xls |  |  |  |  |  |  |  |  |  |
| Old BOM file : E:\barreleye g2\0908\FPDB 0907.xls |  |  |  |  |  |  |  |  |  |
| ##### Add Parts |  |  |  |  |  |  |  |  |  |
| Item | Location | Qty | Foxconn P/N | Part Description | Manufacturer Full Name | Manufacturer P/N | RoHS | Sheet |  |
| 1 | PHAR33 | 1 | 610107A00-017-G | RES,0 Ohm,+/-5%,1/16W,G,SMD0402 | KOA SPEER ELECTRONICS, INC. | RK73Z1ETTP | G | PWA BOM |  |
|  |  |  | 610107A00-012-G | RES,0 Ohm,+/-5%,1/16W,G,SMD0402 | WALSIN TECHNOLOGY CORPORATION | WR04X000PTL | G | PWA BOM |  |
|  |  |  | 610107A00-011-G | RES,0 Ohm,+/-5%,1/16W,G,SMD0402 | YAGEO CORPORATION COMPONENT | RC0402JR-070RL | G | PWA BOM |  |
|  |  |  | 610107A00-044-G | RES,0 Ohm,+/-5%,1/16W,G,SMD0402 | TA-I TECHNOLOGY CO., LTD. | RM04JTN0 | G | PWA BOM |  |
|  |  |  | 610107A00-024-G | RES,0 Ohm,+/-5%,1/16W,G,SMD0402 | PANASONIC INDUSTRIAL CO.,LTD. | ERJ2GE0R00X | G | PWA BOM |  |
|  |  |  | 610107A00-029-G | RES,0 Ohm,+/-5%,1/16W,G,SMD0402 | VISHAY ENTER TECHNO LOGY.INC | CRCW04020000Z0ED | G | PWA BOM |  |
| ##### Remove Parts |  |  |  |  |  |  |  |  |  |
| Item | Location | Qty | Foxconn P/N | Part Description | Manufacturer Full Name | Manufacturer P/N | RoHS | Sheet |  |
| 1 | C71,C72 | 2 | 620101T02-015-G | CAP,100nF,+/-10%,X7R,16V,G,SMD0402 | MURATA ELEC. NORTH AMERICA | GRM155R71C104K | G | PWA BOM |  |
|  |  |  | 620101T00-012-G | CAP,100nF,+/-10%,X7R,16V,G,SMD0402 | WALSIN TECHNOLOGY CORPORATION | 0402B104K160CT | G | PWA BOM |  |
|  |  |  | 620101T00-026-G | CAP,100nF,+/-10%,X7R,16V,G,SMD0402 | SAMSUNG SEMICONDUCTOR | CL05B104KO5NNNC | G | PWA BOM |  |
|  |  |  | 620101T00-015-G | CAP,100nF,+/-10%,X7R,16V,G,SMD0402 | MURATA ELEC. NORTH AMERICA | GRM155R71C104KA88D | G | PWA BOM |  |
| 2 | LED1,LED2 | 2 | 52113DU00-289-G | LED,Hyper Red,LTS-2307CKD-P,G,5V,25mA,G,SMD-10 | LITE-ON TECHNOLOGY CORPORATION | LTS-2307CKD-P | G | PWA BOM |  |
| 3 | PEUR7 | 1 | 610116G00-017-G | RES,150KOhm,+/-1%,1/16W,G,SMD0402 | KOA SPEER ELECTRONICS, INC. | RK73H1ETTP1503F | G | PWA BOM |  |
|  |  |  | 610116G00-011-G | RES,150KOhm,+/-1%,1/16W,G,SMD0402 | YAGEO CORPORATION COMPONENT | RC0402FR-07150KL | G | PWA BOM |  |
|  |  |  | 610116G00-044-G | RES,150KOhm,+/-1%,1/16W,G,SMD0402 | TA-I TECHNOLOGY CO., LTD | RM04FTN1503 | G | PWA BOM |  |
|  |  |  | 610116G00-012-G | RES,150KOhm,+/-1%,1/16W,G,SMD0402 | WALSIN TECHNOLOGY CORPORATION | WR04X1503FTL | G | PWA BOM |  |
| 4 | PSUR4,PEUR6 | 2 | 610118S00-017-G | RES,54.9KOhm,+/-1%,1/16W,G,SMD0402 | KOA SPEER ELECTRONICS, INC. | RK73H1ETTP5492F | G | PWA BOM |  |
|  |  |  | 610118S00-011-G | RES,54.9KOhm,+/-1%,1/16W,G,SMD0402 | YAGEO CORPORATION COMPONENT | RC0402FR-0754K9L |  | PWA BOM |  |
|  |  |  | 610118S00-044-G | RES,54.9KOhm,+/-1%,1/16W,G,SMD0402 | TA-I TECHNOLOGY CO., LTD | RM04FTN5492 |  | PWA BOM |  |
|  |  |  | 610118S00-012-G | RES,54.9KOhm,+/-1%,1/16W,G,SMD0402 | WALSIN TECHNOLOGY CORPORATION | WR04X5492FTL |  | PWA BOM |  |
| 5 | R251 | 1 | 61010L300-017-G | RES,1KOhm,+/-1%,1/16W,G,SMD0402 | KOA SPEER ELECTRONICS, INC. | RK73H1ETTP1001F | G | PWA BOM |  |
|  |  |  | 61010L300-012-G | RES,1KOhm,+/-1%,1/16W,G,SMD0402 | WALSIN TECHNOLOGY CORPORATION | WR04X1001FTL | G | PWA BOM |  |
|  |  |  | 61010L300-011-G | RES,1KOhm,+/-1%,1/16W,G,SMD0402 | YAGEO CORPORATION COMPONENT | RC0402FR-071KL | G | PWA BOM |  |
|  |  |  | 61010L300-044-G | RES,1KOhm,+/-1%,1/16W,G,SMD0402 | TA-I TECHNOLOGY CO., LTD. | RM04FTN1001 | G | PWA BOM |  |
|  |  |  | 61010L300-024-G | RES,1KOhm,+/-1%,1/16W,G,SMD0402 | PANASONIC INDUSTRIAL CO.,LTD. | ERJ2RKF1001X | G | PWA BOM |  |
|  |  |  | 61010L300-029-G | RES,1KOhm,+/-1%,1/16W,G,SMD0402 | VISHAY ENTER TECHNO LOGY.INC | CRCW04021K00FKED | G | PWA BOM |  |
| 6 | PSUR5 | 1 | 61011N000-017-G | RES,68KOhm,+/-1%,1/16W,G,SMD0402 | KOA SPEER ELECTRONICS, INC. | RK73H1ETTP6802F | G | PWA BOM |  |
|  |  |  | 61011N000-011-G | RES,68KOhm,+/-1%,1/16W,G,SMD0402 | YAGEO CORPORATION COMPONENT | RC0402FR-0768KL | G | PWA BOM |  |
|  |  |  | 61011N000-044-G | RES,68KOhm,+/-1%,1/16W,G,SMD0402 | TA-I TECHNOLOGY CO., LTD. | RM04FTN6802 | G | PWA BOM |  |
|  |  |  | 61011N000-012-G | RES,68KOhm,+/-1%,1/16W,G,SMD0402 | WALSIN TECHNOLOGY CORPORATION | WR04X6802FTL | G | PWA BOM |  |
| 7 | R252,R253,R254,R255,R256,R257,R258,R260,R261,R262,R263,R264,R265,R266,R267 | 15 | 61010JY00-017-G | RES,220 Ohm,+/-5%,1/16W,G,SMD0402 | KOA SPEER ELECTRONICS, INC. | RK73B1ETTP221J | G | PWA BOM |  |
|  |  |  | 61010JY00-012-G | RES,220 Ohm,+/-5%,1/16W,G,SMD0402 | WALSIN TECHNOLOGY CORPORATION | WR04X221JTL | G | PWA BOM |  |
|  |  |  | 61010JY00-011-G | RES,220 Ohm,+/-5%,1/16W,G,SMD0402 | YAGEO CORPORATION COMPONENT | RC0402JR-07220RL | G | PWA BOM |  |
|  |  |  | 61010JY00-044-G | RES,220 Ohm,+/-5%,1/16W,G,SMD0402 | TA-I TECHNOLOGY CO., LTD. | RM04JTN221 | G | PWA BOM |  |
| 8 | R250,R259 | 2 | 610107C00-017-G | RES,10KOhm,+/-5%,1/16W,G,SMD0402 | KOA SPEER ELECTRONICS, INC. | RK73B1ETTP103J | G | PWA BOM |  |
|  |  |  | 610107C00-012-G | RES,10KOhm,+/-5%,1/16W,G,SMD0402 | WALSIN TECHNOLOGY CORPORATION | WR04X103JTL | G | PWA BOM |  |
|  |  |  | 610107C00-011-G | RES,10KOhm,+/-5%,1/16W,G,SMD0402 | YAGEO CORPORATION COMPONENT | RC0402JR-0710KL | G | PWA BOM |  |
|  |  |  | 610107C00-044-G | RES,10KOhm,+/-5%,1/16W,G,SMD0402 | TA-I TECHNOLOGY CO., LTD | RM04JTN103 | G | PWA BOM |  |
|  |  |  | 610107C00-024-G | RES,10KOhm,+/-5%,1/16W,G,SMD0402 | PANASONIC INDUSTRIAL CO.,LTD. | ERJ2GEJ103X | G | PWA BOM |  |
|  |  |  | 610107C00-029-G | RES,10KOhm,+/-5%,1/16W,G,SMD0402 | VISHAY ENTER TECHNO LOGY.INC | CRCW040210K0JNED | G | PWA BOM |  |
| 9 | U25,U26 | 2 | 310200R00-183-G | IC,Trigger,SN74LV164ADBR,2~5.5V,G,SSOP-14,SMD | TEXAS INSTRUMENTS | SN74LV164ADBR | G | PWA BOM |  |
| 10 | J10 | 1 | 3406ARH00-309-G | CONN,Header,Socket,V/T,Bla,2.54mm,10u,G,DIP-8 | SAMTEC INC. | ESQ-104-33-L-D | G | PWA BOM |  |
| ##### Change Parts |  |  |  |  |  |  |  |  |  |
| Item | Location | Qty | Foxconn P/N | Part Description | Manufacturer Full Name | Manufacturer P/N | RoHS | Sheet | Remark |
| 1 | R1492 | 1 | 610118800-017-G | RES,499KOhm,+/-1%,1/8W,G,SMD0805 | KOA SPEER ELECTRONICS, INC. | RK73H2ATTD4993F | G | PWA BOM | In New BOM |
|  |  |  | 610118800-024-G | RES,499KOhm,+/-1%,1/8W,G,SMD0805 | PANASONIC INDUSTRIAL CO.,LTD. | ERJ6ENF4993V | G | PWA BOM | In New BOM |
|  |  |  | RC0805FR-07499KL | RES,499KOhm,+/-1%,1/8W,G,SMD0805 | YAGEO CORPORATION COMPONENT | RC0805FR-07499KL | G | PWA BOM | In New BOM |
|  | R1492 | 1 | 610118800-017-G | RES,499KOhm,+/-1%,1/8W,G,SMD0805 | KOA SPEER ELECTRONICS, INC. | RK73H2ATTD4993F | G | PWA BOM | In Old BOM |
|  |  |  | 610118800-024-G | RES,499KOhm,+/-1%,1/8W,G,SMD0805 | PANASONIC INDUSTRIAL CO.,LTD. | ERJ6ENF4993V | G | PWA BOM | In Old BOM |
|  |  |  | RC0805FR-07499KL | RES,499KOhm,+/-1%,1/8W,G,SMD0805 | YAGEO CORPORATION COMPONENT | RC0805FR-07499KL |  | PWA BOM | In Old BOM |
| 2 | PSUR2 | 1 | 610119C00-017-G | RES,130KOhm,+/-1%,1/16W,G,SMD0402 | KOA SPEER ELECTRONICS, INC. | RK73H1ETTP1303F | G | PWA BOM | In New BOM |
|  |  |  | 610119C00-011-G | RES,130KOhm,+/-1%,1/16W,G,SMD0402 | YAGEO CORPORATION COMPONENT | RC0402FR-07130KL | G | PWA BOM | In New BOM |
|  |  |  | 610119C00-012-G | RES,130KOhm,+/-1%,1/16W,G,SMD0402 | WALSIN TECHNOLOGY CORPORATION | WR04X1303FTL | G | PWA BOM | In New BOM |
|  |  |  | 610119C00-044-G | RES,130KOhm,+/-1%,1/16W,G,SMD0402 | TA-I TECHNOLOGY CO., LTD | RM04FTN1303 | G | PWA BOM | In New BOM |
|  | PSUR2 | 1 | 610116G00-017-G | RES,150KOhm,+/-1%,1/16W,G,SMD0402 | KOA SPEER ELECTRONICS, INC. | RK73H1ETTP1503F | G | PWA BOM | In Old BOM |
|  |  |  | 610116G00-011-G | RES,150KOhm,+/-1%,1/16W,G,SMD0402 | YAGEO CORPORATION COMPONENT | RC0402FR-07150KL | G | PWA BOM | In Old BOM |
|  |  |  | 610116G00-044-G | RES,150KOhm,+/-1%,1/16W,G,SMD0402 | TA-I TECHNOLOGY CO., LTD | RM04FTN1503 | G | PWA BOM | In Old BOM |
|  |  |  | 610116G00-012-G | RES,150KOhm,+/-1%,1/16W,G,SMD0402 | WALSIN TECHNOLOGY CORPORATION | WR04X1503FTL | G | PWA BOM | In Old BOM |
| 3 | PEUR2 | 1 | 61010G500-017-G | RES,10KOhm,+/-1%,1/16W,G,SMD0402 | KOA SPEER ELECTRONICS, INC. | RK73H1ETTP1002F | G | PWA BOM | In New BOM |
|  |  |  | 61010G500-012-G | RES,10KOhm,+/-1%,1/16W,G,SMD0402 | WALSIN TECHNOLOGY CORPORATION | WR04X1002FTL | G | PWA BOM | In New BOM |
|  |  |  | 61010G500-011-G | RES,10KOhm,+/-1%,1/16W,G,SMD0402 | YAGEO CORPORATION COMPONENT | RC0402FR-0710KL | G | PWA BOM | In New BOM |
|  |  |  | 61010G500-044-G | RES,10KOhm,+/-1%,1/16W,G,SMD0402 | TA-I TECHNOLOGY CO., LTD. | RM04FTN1002 | G | PWA BOM | In New BOM |
|  |  |  | 61010G500-029-G | RES,10KOhm,+/-1%,1/16W,G,SMD0402 | VISHAY ENTER TECHNO LOGY.INC | CRCW040210K0FKED | G | PWA BOM | In New BOM |
|  |  |  | 61010G500-024-G | RES,10KOhm,+/-1%,1/16W,G,SMD0402 | PANASONIC INDUSTRIAL CO.,LTD. | ERJ2RKF1002X | G | PWA BOM | In New BOM |
|  | PEUR2 | 1 | 610116G00-017-G | RES,150KOhm,+/-1%,1/16W,G,SMD0402 | KOA SPEER ELECTRONICS, INC. | RK73H1ETTP1503F | G | PWA BOM | In Old BOM |
|  |  |  | 610116G00-011-G | RES,150KOhm,+/-1%,1/16W,G,SMD0402 | YAGEO CORPORATION COMPONENT | RC0402FR-07150KL | G | PWA BOM | In Old BOM |
|  |  |  | 610116G00-044-G | RES,150KOhm,+/-1%,1/16W,G,SMD0402 | TA-I TECHNOLOGY CO., LTD | RM04FTN1503 | G | PWA BOM | In Old BOM |
|  |  |  | 610116G00-012-G | RES,150KOhm,+/-1%,1/16W,G,SMD0402 | WALSIN TECHNOLOGY CORPORATION | WR04X1503FTL | G | PWA BOM | In Old BOM |
| 4 | PSUR1 | 1 | 61011GD00-017-G | RES,15.4KOhm,+/-1%,1/16W,G,SMD0402 | KOA SPEER ELECTRONICS, INC. | RK73H1ETTP1542F | G | PWA BOM | In New BOM |
|  |  |  | 61011GD00-011-G | RES,15.4KOhm,+/-1%,1/16W,G,SMD0402 | YAGEO CORPORATION COMPONENT | RC0402FR-0715K4L | G | PWA BOM | In New BOM |
|  |  |  | 61011GD00-012-G | RES,15.4KOhm,+/-1%,1/16W,G,SMD0402 | WALSIN TECHNOLOGY CORPORATION | WR04X1542FTL | G | PWA BOM | In New BOM |
|  |  |  | 61011GD00-044-G | RES,15.4KOhm,+/-1%,1/16W,G,SMD0402 | TA-I TECHNOLOGY CO., LTD. | RM04FTN1542 | G | PWA BOM | In New BOM |
|  | PSUR1 | 1 | 61011NY00-017-G | RES,88.7KOhm,+/-1%,1/16W,G,SMD0402 | KOA SPEER ELECTRONICS, INC. | RK73H1ETTP8872F | G | PWA BOM | In Old BOM |
|  |  |  | 61011NY00-011-G | RES,88.7KOhm,+/-1%,1/16W,G,SMD0402 | YAGEO CORPORATION COMPONENT | RC0402FR-0788K7L | G | PWA BOM | In Old BOM |
|  |  |  | 61011NY00-012-G | RES,88.7KOhm,+/-1%,1/16W,G,SMD0402 | WALSIN TECHNOLOGY CORPORATION | WR04X8872FTL | G | PWA BOM | In Old BOM |
| ##### Change Revision |  |  |  |  |  |  |  |  |  |
| Sheet | REV OF BOM | CUSTOMER | CUSTOMER P/N | PWA PN | PWA DESCRIPTION | PWA REV | DATE | Remark |  |
| OOOOOOOOOOOOOOOOOOOOOOOOOOOOOOOOOOOOOOOOOOOOOOOOOOOOOOOOOOOOOOOOOOOOOOOOOOOOOOOOOOOOOOOOOO | OOOOOOOOOOOOOOOOOOOOOOOOOOOOOOOOOOOOOOOOOOOOOOOOOOOOOOOOOOOOOOOOOOOOOOOOOOOOOOOOOOOOOOOOOO | OOOOOOOOOOOOOOOOOOOOOOOOOOOOOOOOOOOOOOOOOOOOOOOOOOOOOOOOOOOOOOOOOOOOOOOOOOOOOOOOOOOOOOOOOO | OOOOOOOOOOOOOOOOOOOOOOOOOOOOOOOOOOOOOOOOOOOOOOOOOOOOOOOOOOOOOOOOOOOOOOOOOOOOOOOOOOOOOOOOOO | OOOOOOOOOOOOOOOOOOOOOOOOOOOOOOOOOOOOOOOOOOOOOOOOOOOOOOOOOOOOOOOOOOOOOOOOOOOOOOOOOOOOOOOOOO | OOOOOOOOOOOOOOOOOOOOOOOOOOOOOOOOOOOOOOOOOOOOOOOOOOOOOOOOOOOOOOOOOOOOOOOOOOOOOOOOOOOOOOOOOO | OOOOOOOOOOOOOOOOOOOOOOOOOOOOOOOOOOOOOOOOOOOOOOOOOOOOOOOOOOOOOOOOOOOOOOOOOOOOOOOOOOOOOOOOOO | OOOOOOOOOOOOOOOOOOOOOOOOOOOOOOOOOOOOOOOOOOOOOOOOOOOOOOOOOOOOOOOOOOOOOOOOOOOOOOOOOOOOOOOOOO | OOOOOOOOOOOOOOOOOOOOOOOOOOOOOOOOOOOOOOOOOOOOOOOOOOOOOOOOOOOOOOOOOOOOOOOOOOOOOOOOOOOOOOOOOO | OOOOOOOOOOOOOOOOOOOOOOOOOOOOOOOOOOOOOOOOOOOOOOOOOOOOOOOOOOOOOOOOOOOOOOOOOOOOOOOOOOOOOOOOOO |
| Second Source Change |  |  |  |  |  |  |  |  |  |
| Item | Location | Change Type | Foxconn P/N | Part Description | Manufacturer Full Name | Manufacturer P/N | RoHS | Sheet |  |
| OOOOOOOOOOOOOOOOOOOOOOOOOOOOOOOOOOOOOOOOOOOOOOOOOOOOOOOOOOOOOOOOOOOOOOOOOOOOOOOOOOOOOOOOOO | OOOOOOOOOOOOOOOOOOOOOOOOOOOOOOOOOOOOOOOOOOOOOOOOOOOOOOOOOOOOOOOOOOOOOOOOOOOOOOOOOOOOOOOOOO | OOOOOOOOOOOOOOOOOOOOOOOOOOOOOOOOOOOOOOOOOOOOOOOOOOOOOOOOOOOOOOOOOOOOOOOOOOOOOOOOOOOOOOOOOO | OOOOOOOOOOOOOOOOOOOOOOOOOOOOOOOOOOOOOOOOOOOOOOOOOOOOOOOOOOOOOOOOOOOOOOOOOOOOOOOOOOOOOOOOOO | OOOOOOOOOOOOOOOOOOOOOOOOOOOOOOOOOOOOOOOOOOOOOOOOOOOOOOOOOOOOOOOOOOOOOOOOOOOOOOOOOOOOOOOOOO | OOOOOOOOOOOOOOOOOOOOOOOOOOOOOOOOOOOOOOOOOOOOOOOOOOOOOOOOOOOOOOOOOOOOOOOOOOOOOOOOOOOOOOOOOO | OOOOOOOOOOOOOOOOOOOOOOOOOOOOOOOOOOOOOOOOOOOOOOOOOOOOOOOOOOOOOOOOOOOOOOOOOOOOOOOOOOOOOOOOOO | OOOOOOOOOOOOOOOOOOOOOOOOOOOOOOOOOOOOOOOOOOOOOOOOOOOOOOOOOOOOOOOOOOOOOOOOOOOOOOOOOOOOOOOOOO | OOOOOOOOOOOOOOOOOOOOOOOOOOOOOOOOOOOOOOOOOOOOOOOOOOOOOOOOOOOOOOOOOOOOOOOOOOOOOOOOOOOOOOOOOO | OOOOOOOOOOOOOOOOOOOOOOOOOOOOOOOOOOOOOOOOOOOOOOOOOOOOOOOOOOOOOOOOOOOOOOOOOOOOOOOOOOOOOOOOOO |
| Master Materials Change |  |  |  |  |  |  |  |  |  |
| Item | Foxconn P/N | Orig._Usage | New_Usage | Part Description | Manufacturer Full Name | Manufacturer P/N | RoHS | Location | Sheet |
| 1 | 620101T02-015-G | 19 | 17 | CAP,100nF,+/-10%,X7R,16V,G,SMD0402 | MURATA ELEC. NORTH AMERICA | GRM155R71C104K | G | (-)C71,C72 | PWA BOM |
|  | 620101T00-012-G |  |  | CAP,100nF,+/-10%,X7R,16V,G,SMD0402 | WALSIN TECHNOLOGY CORPORATION | 0402B104K160CT |  |  | PWA BOM |
|  | 620101T00-026-G |  |  | CAP,100nF,+/-10%,X7R,16V,G,SMD0402 | SAMSUNG SEMICONDUCTOR | CL05B104KO5NNNC |  |  | PWA BOM |
|  | 620101T00-015-G |  |  | CAP,100nF,+/-10%,X7R,16V,G,SMD0402 | MURATA ELEC. NORTH AMERICA | GRM155R71C104KA88D |  |  | PWA BOM |
| 2 | 610119C00-017-G | 1 | 2 | RES,130KOhm,+/-1%,1/16W,G,SMD0402 | KOA SPEER ELECTRONICS, INC. | RK73H1ETTP1303F | G | (+)PSUR2 | PWA BOM |
|  | 610119C00-011-G |  |  | RES,130KOhm,+/-1%,1/16W,G,SMD0402 | YAGEO CORPORATION COMPONENT | RC0402FR-07130KL |  |  | PWA BOM |
|  | 610119C00-012-G |  |  | RES,130KOhm,+/-1%,1/16W,G,SMD0402 | WALSIN TECHNOLOGY CORPORATION | WR04X1303FTL |  |  | PWA BOM |
|  | 610119C00-044-G |  |  | RES,130KOhm,+/-1%,1/16W,G,SMD0402 | TA-I TECHNOLOGY CO., LTD | RM04FTN1303 |  |  | PWA BOM |
| 3 | 61010G500-017-G | 17 | 18 | RES,10KOhm,+/-1%,1/16W,G,SMD0402 | KOA SPEER ELECTRONICS, INC. | RK73H1ETTP1002F | G | (+)PEUR2 | PWA BOM |
|  | 61010G500-012-G |  |  | RES,10KOhm,+/-1%,1/16W,G,SMD0402 | WALSIN TECHNOLOGY CORPORATION | WR04X1002FTL |  |  | PWA BOM |
|  | 61010G500-011-G |  |  | RES,10KOhm,+/-1%,1/16W,G,SMD0402 | YAGEO CORPORATION COMPONENT | RC0402FR-0710KL |  |  | PWA BOM |
|  | 61010G500-044-G |  |  | RES,10KOhm,+/-1%,1/16W,G,SMD0402 | TA-I TECHNOLOGY CO., LTD. | RM04FTN1002 |  |  | PWA BOM |
|  | 61010G500-029-G |  |  | RES,10KOhm,+/-1%,1/16W,G,SMD0402 | VISHAY ENTER TECHNO LOGY.INC | CRCW040210K0FKED |  |  | PWA BOM |
|  | 61010G500-024-G |  |  | RES,10KOhm,+/-1%,1/16W,G,SMD0402 | PANASONIC INDUSTRIAL CO.,LTD. | ERJ2RKF1002X |  |  | PWA BOM |
| 4 | 610107A00-017-G | 64 | 65 | RES,0 Ohm,+/-5%,1/16W,G,SMD0402 | KOA SPEER ELECTRONICS, INC. | RK73Z1ETTP | G | (+)PHAR33 | PWA BOM |
|  | 610107A00-012-G |  |  | RES,0 Ohm,+/-5%,1/16W,G,SMD0402 | WALSIN TECHNOLOGY CORPORATION | WR04X000PTL |  |  | PWA BOM |
|  | 610107A00-011-G |  |  | RES,0 Ohm,+/-5%,1/16W,G,SMD0402 | YAGEO CORPORATION COMPONENT | RC0402JR-070RL |  |  | PWA BOM |
|  | 610107A00-044-G |  |  | RES,0 Ohm,+/-5%,1/16W,G,SMD0402 | TA-I TECHNOLOGY CO., LTD. | RM04JTN0 |  |  | PWA BOM |
|  | 610107A00-024-G |  |  | RES,0 Ohm,+/-5%,1/16W,G,SMD0402 | PANASONIC INDUSTRIAL CO.,LTD. | ERJ2GE0R00X |  |  | PWA BOM |
|  | 610107A00-029-G |  |  | RES,0 Ohm,+/-5%,1/16W,G,SMD0402 | VISHAY ENTER TECHNO LOGY.INC | CRCW04020000Z0ED |  |  | PWA BOM |
| 5 | 61010L300-017-G | 2 | 1 | RES,1KOhm,+/-1%,1/16W,G,SMD0402 | KOA SPEER ELECTRONICS, INC. | RK73H1ETTP1001F | G | (-)R251 | PWA BOM |
|  | 61010L300-012-G |  |  | RES,1KOhm,+/-1%,1/16W,G,SMD0402 | WALSIN TECHNOLOGY CORPORATION | WR04X1001FTL |  |  | PWA BOM |
|  | 61010L300-011-G |  |  | RES,1KOhm,+/-1%,1/16W,G,SMD0402 | YAGEO CORPORATION COMPONENT | RC0402FR-071KL |  |  | PWA BOM |
|  | 61010L300-044-G |  |  | RES,1KOhm,+/-1%,1/16W,G,SMD0402 | TA-I TECHNOLOGY CO., LTD. | RM04FTN1001 |  |  | PWA BOM |
|  | 61010L300-024-G |  |  | RES,1KOhm,+/-1%,1/16W,G,SMD0402 | PANASONIC INDUSTRIAL CO.,LTD. | ERJ2RKF1001X |  |  | PWA BOM |
|  | 61010L300-029-G |  |  | RES,1KOhm,+/-1%,1/16W,G,SMD0402 | VISHAY ENTER TECHNO LOGY.INC | CRCW04021K00FKED |  |  | PWA BOM |
| 6 | 61011GD00-017-G | 0 | 1 | RES,15.4KOhm,+/-1%,1/16W,G,SMD0402 | KOA SPEER ELECTRONICS, INC. | RK73H1ETTP1542F | G | (+)PSUR1 | PWA BOM |
|  | 61011GD00-011-G |  |  | RES,15.4KOhm,+/-1%,1/16W,G,SMD0402 | YAGEO CORPORATION COMPONENT | RC0402FR-0715K4L |  |  | PWA BOM |
|  | 61011GD00-012-G |  |  | RES,15.4KOhm,+/-1%,1/16W,G,SMD0402 | WALSIN TECHNOLOGY CORPORATION | WR04X1542FTL |  |  | PWA BOM |
|  | 61011GD00-044-G |  |  | RES,15.4KOhm,+/-1%,1/16W,G,SMD0402 | TA-I TECHNOLOGY CO., LTD. | RM04FTN1542 |  |  | PWA BOM |
| 7 | 61010JY00-017-G | 18 | 3 | RES,220 Ohm,+/-5%,1/16W,G,SMD0402 | KOA SPEER ELECTRONICS, INC. | RK73B1ETTP221J | G | (-)R252,R253,R254,R255,R256,R257,R258,R260,R261,R262,R263,R264,R265,R266,R267 | PWA BOM |
|  | 61010JY00-012-G |  |  | RES,220 Ohm,+/-5%,1/16W,G,SMD0402 | WALSIN TECHNOLOGY CORPORATION | WR04X221JTL |  |  | PWA BOM |
|  | 61010JY00-011-G |  |  | RES,220 Ohm,+/-5%,1/16W,G,SMD0402 | YAGEO CORPORATION COMPONENT | RC0402JR-07220RL |  |  | PWA BOM |
|  | 61010JY00-044-G |  |  | RES,220 Ohm,+/-5%,1/16W,G,SMD0402 | TA-I TECHNOLOGY CO., LTD. | RM04JTN221 |  |  | PWA BOM |
| 8 | 52113DU00-289-G | 2 | 0 | LED,Hyper Red,LTS-2307CKD-P,G,5V,25mA,G,SMD-10 | LITE-ON TECHNOLOGY CORPORATION | LTS-2307CKD-P | G | (-)LED1,LED2 | PWA BOM |
| 9 | 610116G00-017-G | 3 | 0 | RES,150KOhm,+/-1%,1/16W,G,SMD0402 | KOA SPEER ELECTRONICS, INC. | RK73H1ETTP1503F | G | (-)PSUR2,PEUR2,PEUR7 | PWA BOM |
|  | 610116G00-011-G |  |  | RES,150KOhm,+/-1%,1/16W,G,SMD0402 | YAGEO CORPORATION COMPONENT | RC0402FR-07150KL |  |  | PWA BOM |
|  | 610116G00-044-G |  |  | RES,150KOhm,+/-1%,1/16W,G,SMD0402 | TA-I TECHNOLOGY CO., LTD | RM04FTN1503 |  |  | PWA BOM |
|  | 610116G00-012-G |  |  | RES,150KOhm,+/-1%,1/16W,G,SMD0402 | WALSIN TECHNOLOGY CORPORATION | WR04X1503FTL |  |  | PWA BOM |
| 10 | 610118S00-017-G | 2 | 0 | RES,54.9KOhm,+/-1%,1/16W,G,SMD0402 | KOA SPEER ELECTRONICS, INC. | RK73H1ETTP5492F | G | (-)PSUR4,PEUR6 | PWA BOM |
|  | 610118S00-011-G |  |  | RES,54.9KOhm,+/-1%,1/16W,G,SMD0402 | YAGEO CORPORATION COMPONENT | RC0402FR-0754K9L |  |  | PWA BOM |
|  | 610118S00-044-G |  |  | RES,54.9KOhm,+/-1%,1/16W,G,SMD0402 | TA-I TECHNOLOGY CO., LTD | RM04FTN5492 |  |  | PWA BOM |
|  | 610118S00-012-G |  |  | RES,54.9KOhm,+/-1%,1/16W,G,SMD0402 | WALSIN TECHNOLOGY CORPORATION | WR04X5492FTL |  |  | PWA BOM |
| 11 | 61011NY00-017-G | 1 | 0 | RES,88.7KOhm,+/-1%,1/16W,G,SMD0402 | KOA SPEER ELECTRONICS, INC. | RK73H1ETTP8872F | G | (-)PSUR1 | PWA BOM |
|  | 61011NY00-011-G |  |  | RES,88.7KOhm,+/-1%,1/16W,G,SMD0402 | YAGEO CORPORATION COMPONENT | RC0402FR-0788K7L |  |  | PWA BOM |
|  | 61011NY00-012-G |  |  | RES,88.7KOhm,+/-1%,1/16W,G,SMD0402 | WALSIN TECHNOLOGY CORPORATION | WR04X8872FTL |  |  | PWA BOM |
| 12 | 61011N000-017-G | 1 | 0 | RES,68KOhm,+/-1%,1/16W,G,SMD0402 | KOA SPEER ELECTRONICS, INC. | RK73H1ETTP6802F | G | (-)PSUR5 | PWA BOM |
|  | 61011N000-011-G |  |  | RES,68KOhm,+/-1%,1/16W,G,SMD0402 | YAGEO CORPORATION COMPONENT | RC0402FR-0768KL |  |  | PWA BOM |
|  | 61011N000-044-G |  |  | RES,68KOhm,+/-1%,1/16W,G,SMD0402 | TA-I TECHNOLOGY CO., LTD. | RM04FTN6802 |  |  | PWA BOM |
|  | 61011N000-012-G |  |  | RES,68KOhm,+/-1%,1/16W,G,SMD0402 | WALSIN TECHNOLOGY CORPORATION | WR04X6802FTL |  |  | PWA BOM |
| 13 | 610107C00-017-G | 2 | 0 | RES,10KOhm,+/-5%,1/16W,G,SMD0402 | KOA SPEER ELECTRONICS, INC. | RK73B1ETTP103J | G | (-)R250,R259 | PWA BOM |
|  | 610107C00-012-G |  |  | RES,10KOhm,+/-5%,1/16W,G,SMD0402 | WALSIN TECHNOLOGY CORPORATION | WR04X103JTL |  |  | PWA BOM |
|  | 610107C00-011-G |  |  | RES,10KOhm,+/-5%,1/16W,G,SMD0402 | YAGEO CORPORATION COMPONENT | RC0402JR-0710KL |  |  | PWA BOM |
|  | 610107C00-044-G |  |  | RES,10KOhm,+/-5%,1/16W,G,SMD0402 | TA-I TECHNOLOGY CO., LTD | RM04JTN103 |  |  | PWA BOM |
|  | 610107C00-024-G |  |  | RES,10KOhm,+/-5%,1/16W,G,SMD0402 | PANASONIC INDUSTRIAL CO.,LTD. | ERJ2GEJ103X |  |  | PWA BOM |
|  | 610107C00-029-G |  |  | RES,10KOhm,+/-5%,1/16W,G,SMD0402 | VISHAY ENTER TECHNO LOGY.INC | CRCW040210K0JNED |  |  | PWA BOM |
| 14 | 310200R00-183-G | 2 | 0 | IC,Trigger,SN74LV164ADBR,2~5.5V,G,SSOP-14,SMD | TEXAS INSTRUMENTS | SN74LV164ADBR | G | (-)U25,U26 | PWA BOM |
| 15 | 3406ARH00-309-G | 1 | 0 | CONN,Header,Socket,V/T,Bla,2.54mm,10u,G,DIP-8 | SAMTEC INC. | ESQ-104-33-L-D | G | (-)J10 | PWA BOM |
| OOOOOOOOOOOOOOOOOOOOOOOOOOOOOOOOOOOOOOOOOOOOOOOOOOOOOOOOOOOOOOOOOOOOOOOOOOOOOOOOOOOOOOOOOO | OOOOOOOOOOOOOOOOOOOOOOOOOOOOOOOOOOOOOOOOOOOOOOOOOOOOOOOOOOOOOOOOOOOOOOOOOOOOOOOOOOOOOOOOOO | OOOOOOOOOOOOOOOOOOOOOOOOOOOOOOOOOOOOOOOOOOOOOOOOOOOOOOOOOOOOOOOOOOOOOOOOOOOOOOOOOOOOOOOOOO | OOOOOOOOOOOOOOOOOOOOOOOOOOOOOOOOOOOOOOOOOOOOOOOOOOOOOOOOOOOOOOOOOOOOOOOOOOOOOOOOOOOOOOOOOO | OOOOOOOOOOOOOOOOOOOOOOOOOOOOOOOOOOOOOOOOOOOOOOOOOOOOOOOOOOOOOOOOOOOOOOOOOOOOOOOOOOOOOOOOOO | OOOOOOOOOOOOOOOOOOOOOOOOOOOOOOOOOOOOOOOOOOOOOOOOOOOOOOOOOOOOOOOOOOOOOOOOOOOOOOOOOOOOOOOOOO | OOOOOOOOOOOOOOOOOOOOOOOOOOOOOOOOOOOOOOOOOOOOOOOOOOOOOOOOOOOOOOOOOOOOOOOOOOOOOOOOOOOOOOOOOO | OOOOOOOOOOOOOOOOOOOOOOOOOOOOOOOOOOOOOOOOOOOOOOOOOOOOOOOOOOOOOOOOOOOOOOOOOOOOOOOOOOOOOOOOOO | OOOOOOOOOOOOOOOOOOOOOOOOOOOOOOOOOOOOOOOOOOOOOOOOOOOOOOOOOOOOOOOOOOOOOOOOOOOOOOOOOOOOOOOOOO | OOOOOOOOOOOOOOOOOOOOOOOOOOOOOOOOOOOOOOOOOOOOOOOOOOOOOOOOOOOOOOOOOOOOOOOOOOOOOOOOOOOOOOOOOO |
| TLA Parts Change |  |  |  |  |  |  |  |  |  |
| Item | Foxconn P/N | Qty | Part Description | Manufacturer Full Name | Manufacturer P/N | RoHS | Location | Remark | BOM |
| BOM Change List Date:Tue Sep 12 17:23:02 CST 2017 |  |  |  |  |  |  |  |  |  |
| New BOM file : E:\barreleye g2\0912\fpdb foxbis\FPDB 0912.xls |  |  |  |  |  |  |  |  |  |
| Old BOM file : E:\barreleye g2\0912\fpdb foxbis\FPDB 0911.xls |  |  |  |  |  |  |  |  |  |
| ##### Add Parts |  |  |  |  |  |  |  |  |  |
| Item | Location | Qty | Foxconn P/N | Part Description | Manufacturer Full Name | Manufacturer P/N | RoHS | Sheet |  |
| ##### Remove Parts |  |  |  |  |  |  |  |  |  |
| Item | Location | Qty | Foxconn P/N | Part Description | Manufacturer Full Name | Manufacturer P/N | RoHS | Sheet |  |
| ##### Change Parts |  |  |  |  |  |  |  |  |  |
| Item | Location | Qty | Foxconn P/N | Part Description | Manufacturer Full Name | Manufacturer P/N | RoHS | Sheet | Remark |
| 1 | U_FPDB_FRU | 1 | 41040HW00-191-G | EEPROM,AT24C02D-SSHM-T,1.7~3.6V,2K,I2C,G,SOIC-8,SMD | ATMEL CORPORATION | AT24C02D-SSHM-T | G | PWA BOM | In New BOM |
|  |  |  | 410401W00-214-G | EEPROM,M24C02-WMN6TP,2.5~5.5V,256*8,I2C,G,SOIC-8,SMD | ST MICRO ELECTRONICS,INC | M24C02-WMN6TP |  | PWA BOM | In New BOM |
|  |  |  | 41040J500-232-G | EEPROM,24AA024T-I/SN,1.7V~5.5V,2K,I2C,G,SOIC-8,SMD | MICROCHIP TECHNOLOGY INC | 24AA024-I/SN |  | PWA BOM | In New BOM |
|  | U_FPDB_FRU | 1 | 41040HW00-191-G | EEPROM,AT24C02D-SSHM-T,1.7~3.6V,2K,I2C,G,SOIC-8,SMD | ATMEL CORPORATION | 24AA024T-I/SN | G | PWA BOM | In Old BOM |
| ##### Change Revision |  |  |  |  |  |  |  |  |  |
| Sheet | REV OF BOM | CUSTOMER | CUSTOMER P/N | PWA PN | PWA DESCRIPTION | PWA REV | DATE | Remark |  |
| OOOOOOOOOOOOOOOOOOOOOOOOOOOOOOOOOOOOOOOOOOOOOOOOOOOOOOOOOOOOOOOOOOOOOOOOOOOOOOOOOOOOOOOOOO | OOOOOOOOOOOOOOOOOOOOOOOOOOOOOOOOOOOOOOOOOOOOOOOOOOOOOOOOOOOOOOOOOOOOOOOOOOOOOOOOOOOOOOOOOO | OOOOOOOOOOOOOOOOOOOOOOOOOOOOOOOOOOOOOOOOOOOOOOOOOOOOOOOOOOOOOOOOOOOOOOOOOOOOOOOOOOOOOOOOOO | OOOOOOOOOOOOOOOOOOOOOOOOOOOOOOOOOOOOOOOOOOOOOOOOOOOOOOOOOOOOOOOOOOOOOOOOOOOOOOOOOOOOOOOOOO | OOOOOOOOOOOOOOOOOOOOOOOOOOOOOOOOOOOOOOOOOOOOOOOOOOOOOOOOOOOOOOOOOOOOOOOOOOOOOOOOOOOOOOOOOO | OOOOOOOOOOOOOOOOOOOOOOOOOOOOOOOOOOOOOOOOOOOOOOOOOOOOOOOOOOOOOOOOOOOOOOOOOOOOOOOOOOOOOOOOOO | OOOOOOOOOOOOOOOOOOOOOOOOOOOOOOOOOOOOOOOOOOOOOOOOOOOOOOOOOOOOOOOOOOOOOOOOOOOOOOOOOOOOOOOOOO | OOOOOOOOOOOOOOOOOOOOOOOOOOOOOOOOOOOOOOOOOOOOOOOOOOOOOOOOOOOOOOOOOOOOOOOOOOOOOOOOOOOOOOOOOO | OOOOOOOOOOOOOOOOOOOOOOOOOOOOOOOOOOOOOOOOOOOOOOOOOOOOOOOOOOOOOOOOOOOOOOOOOOOOOOOOOOOOOOOOOO | OOOOOOOOOOOOOOOOOOOOOOOOOOOOOOOOOOOOOOOOOOOOOOOOOOOOOOOOOOOOOOOOOOOOOOOOOOOOOOOOOOOOOOOOOO |
| Second Source Change |  |  |  |  |  |  |  |  |  |
| Item | Location | Change Type | Foxconn P/N | Part Description | Manufacturer Full Name | Manufacturer P/N | RoHS | Sheet |  |
| 1 | U_FPDB_FRU |  | 41040HW00-191-G | EEPROM,AT24C02D-SSHM-T,1.7~3.6V,2K,I2C,G,SOIC-8,SMD | ATMEL CORPORATION | AT24C02D-SSHM-T | G | PWA BOM |  |
|  |  | ADD | 410401W00-214-G | EEPROM,M24C02-WMN6TP,2.5~5.5V,256*8,I2C,G,SOIC-8,SMD | ST MICRO ELECTRONICS,INC | M24C02-WMN6TP |  | PWA BOM |  |
|  |  | ADD | 41040J500-232-G | EEPROM,24AA024T-I/SN,1.7V~5.5V,2K,I2C,G,SOIC-8,SMD | MICROCHIP TECHNOLOGY INC | 24AA024T-I/SN |  | PWA BOM |  |
| OOOOOOOOOOOOOOOOOOOOOOOOOOOOOOOOOOOOOOOOOOOOOOOOOOOOOOOOOOOOOOOOOOOOOOOOOOOOOOOOOOOOOOOOOO | OOOOOOOOOOOOOOOOOOOOOOOOOOOOOOOOOOOOOOOOOOOOOOOOOOOOOOOOOOOOOOOOOOOOOOOOOOOOOOOOOOOOOOOOOO | OOOOOOOOOOOOOOOOOOOOOOOOOOOOOOOOOOOOOOOOOOOOOOOOOOOOOOOOOOOOOOOOOOOOOOOOOOOOOOOOOOOOOOOOOO | OOOOOOOOOOOOOOOOOOOOOOOOOOOOOOOOOOOOOOOOOOOOOOOOOOOOOOOOOOOOOOOOOOOOOOOOOOOOOOOOOOOOOOOOOO | OOOOOOOOOOOOOOOOOOOOOOOOOOOOOOOOOOOOOOOOOOOOOOOOOOOOOOOOOOOOOOOOOOOOOOOOOOOOOOOOOOOOOOOOOO | OOOOOOOOOOOOOOOOOOOOOOOOOOOOOOOOOOOOOOOOOOOOOOOOOOOOOOOOOOOOOOOOOOOOOOOOOOOOOOOOOOOOOOOOOO | OOOOOOOOOOOOOOOOOOOOOOOOOOOOOOOOOOOOOOOOOOOOOOOOOOOOOOOOOOOOOOOOOOOOOOOOOOOOOOOOOOOOOOOOOO | OOOOOOOOOOOOOOOOOOOOOOOOOOOOOOOOOOOOOOOOOOOOOOOOOOOOOOOOOOOOOOOOOOOOOOOOOOOOOOOOOOOOOOOOOO | OOOOOOOOOOOOOOOOOOOOOOOOOOOOOOOOOOOOOOOOOOOOOOOOOOOOOOOOOOOOOOOOOOOOOOOOOOOOOOOOOOOOOOOOOO | OOOOOOOOOOOOOOOOOOOOOOOOOOOOOOOOOOOOOOOOOOOOOOOOOOOOOOOOOOOOOOOOOOOOOOOOOOOOOOOOOOOOOOOOOO |
| Master Materials Change |  |  |  |  |  |  |  |  |  |
| Item | Foxconn P/N | Orig._Usage | New_Usage | Part Description | Manufacturer Full Name | Manufacturer P/N | RoHS | Location | Sheet |
| OOOOOOOOOOOOOOOOOOOOOOOOOOOOOOOOOOOOOOOOOOOOOOOOOOOOOOOOOOOOOOOOOOOOOOOOOOOOOOOOOOOOOOOOOO | OOOOOOOOOOOOOOOOOOOOOOOOOOOOOOOOOOOOOOOOOOOOOOOOOOOOOOOOOOOOOOOOOOOOOOOOOOOOOOOOOOOOOOOOOO | OOOOOOOOOOOOOOOOOOOOOOOOOOOOOOOOOOOOOOOOOOOOOOOOOOOOOOOOOOOOOOOOOOOOOOOOOOOOOOOOOOOOOOOOOO | OOOOOOOOOOOOOOOOOOOOOOOOOOOOOOOOOOOOOOOOOOOOOOOOOOOOOOOOOOOOOOOOOOOOOOOOOOOOOOOOOOOOOOOOOO | OOOOOOOOOOOOOOOOOOOOOOOOOOOOOOOOOOOOOOOOOOOOOOOOOOOOOOOOOOOOOOOOOOOOOOOOOOOOOOOOOOOOOOOOOO | OOOOOOOOOOOOOOOOOOOOOOOOOOOOOOOOOOOOOOOOOOOOOOOOOOOOOOOOOOOOOOOOOOOOOOOOOOOOOOOOOOOOOOOOOO | OOOOOOOOOOOOOOOOOOOOOOOOOOOOOOOOOOOOOOOOOOOOOOOOOOOOOOOOOOOOOOOOOOOOOOOOOOOOOOOOOOOOOOOOOO | OOOOOOOOOOOOOOOOOOOOOOOOOOOOOOOOOOOOOOOOOOOOOOOOOOOOOOOOOOOOOOOOOOOOOOOOOOOOOOOOOOOOOOOOOO | OOOOOOOOOOOOOOOOOOOOOOOOOOOOOOOOOOOOOOOOOOOOOOOOOOOOOOOOOOOOOOOOOOOOOOOOOOOOOOOOOOOOOOOOOO | OOOOOOOOOOOOOOOOOOOOOOOOOOOOOOOOOOOOOOOOOOOOOOOOOOOOOOOOOOOOOOOOOOOOOOOOOOOOOOOOOOOOOOOOOO |
| TLA Parts Change |  |  |  |  |  |  |  |  |  |
| Item | Foxconn P/N | Qty | Part Description | Manufacturer Full Name | Manufacturer P/N | RoHS | Location | Remark | BOM |
| BOM Change List Date:Fri Sep 22 14:34:33 GMT+08:00 2017 |  |  |  |  |  |  |  |  |  |
| New BOM file : C:\<user>\BARRELEYE_G2-FPDB_POST-PVT-X02-BOM-X04-20170922.xls |  |  |  |  |  |  |  |  |  |
| Old BOM file : C:\<user>\FPDB 0914ç»_x009d_å¯¹å®_x008c_ç¾_x008e_.xls |  |  |  |  |  |  |  |  |  |
| ##### Add Parts |  |  |  |  |  |  |  |  |  |
| Item | Location | Qty | Foxconn P/N | Part Description | Manufacturer Full Name | Manufacturer P/N | RoHS | Sheet |  |
| ##### Remove Parts |  |  |  |  |  |  |  |  |  |
| Item | Location | Qty | Foxconn P/N | Part Description | Manufacturer Full Name | Manufacturer P/N | RoHS | Sheet |  |
| ##### Change Parts |  |  |  |  |  |  |  |  |  |
| Item | Location | Qty | Foxconn P/N | Part Description | Manufacturer Full Name | Manufacturer P/N | RoHS | Sheet | Remark |
| 1 | PHAR35 | 1 | 610113D00-017-G | RES,10.5KOhm,+/-1%,1/16W,G,SMD0402 | KOA SPEER ELECTRONICS, INC. | RK73H1ETTP1052F | G | PWA BOM | In New BOM |
|  |  |  | 610113D00-011-G | RES,10.5KOhm,+/-1%,1/16W,G,SMD0402 | YAGEO CORPORATION COMPONENT | RC0402FR-0710K5L |  | PWA BOM | In New BOM |
|  |  |  | 610113D00-012-G | RES,10.5KOhm,+/-1%,1/16W,G,SMD0402 | WALSIN TECHNOLOGY CORPORATION | WR04X1052FTL |  | PWA BOM | In New BOM |
|  |  |  | 610113D00-044-G | RES,10.5KOhm,+/-1%,1/16W,G,SMD0402 | TA-I TECHNOLOGY CO., LTD. | RM04FTN1052 |  | PWA BOM | In New BOM |
|  | PHAR35 | 1 | 61011PE00-017-G | RES,8.87KOhm,+/-1%,1/16W,G,SMD0402 | KOA SPEER ELECTRONICS, INC. | RK73H1ETTP8871F | G | PWA BOM | In Old BOM |
|  |  |  | 61011PE00-012-G | RES,8.87KOhm,+/-1%,1/16W,G,SMD0402 | WALSIN TECHNOLOGY CORPORATION | WR04X8871FTL | G | PWA BOM | In Old BOM |
|  |  |  | 61011PE00-011-G | RES,8.87KOhm,+/-1%,1/16W,G,SMD0402 | YAGEO CORPORATION COMPONENT | RC0402FR-078K87L | G | PWA BOM | In Old BOM |
|  |  |  | 61011PE00-044-G | RES,8.87KOhm,+/-1%,1/16W,G,SMD0402 | TA-I TECHNOLOGY CO., LTD. | RM04FTN8871 | G | PWA BOM | In Old BOM |
| ##### Change Revision |  |  |  |  |  |  |  |  |  |
| Sheet | REV OF BOM | CUSTOMER | CUSTOMER P/N | PWA PN | PWA DESCRIPTION | PWA REV | DATE | Remark |  |
| OOOOOOOOOOOOOOOOOOOOOOOOOOOOOOOOOOOOOOOOOOOOOOOOOOOOOOOOOOOOOOOOOOOOOOOOOOOOOOOOOOOOOOOOOO | OOOOOOOOOOOOOOOOOOOOOOOOOOOOOOOOOOOOOOOOOOOOOOOOOOOOOOOOOOOOOOOOOOOOOOOOOOOOOOOOOOOOOOOOOO | OOOOOOOOOOOOOOOOOOOOOOOOOOOOOOOOOOOOOOOOOOOOOOOOOOOOOOOOOOOOOOOOOOOOOOOOOOOOOOOOOOOOOOOOOO | OOOOOOOOOOOOOOOOOOOOOOOOOOOOOOOOOOOOOOOOOOOOOOOOOOOOOOOOOOOOOOOOOOOOOOOOOOOOOOOOOOOOOOOOOO | OOOOOOOOOOOOOOOOOOOOOOOOOOOOOOOOOOOOOOOOOOOOOOOOOOOOOOOOOOOOOOOOOOOOOOOOOOOOOOOOOOOOOOOOOO | OOOOOOOOOOOOOOOOOOOOOOOOOOOOOOOOOOOOOOOOOOOOOOOOOOOOOOOOOOOOOOOOOOOOOOOOOOOOOOOOOOOOOOOOOO | OOOOOOOOOOOOOOOOOOOOOOOOOOOOOOOOOOOOOOOOOOOOOOOOOOOOOOOOOOOOOOOOOOOOOOOOOOOOOOOOOOOOOOOOOO | OOOOOOOOOOOOOOOOOOOOOOOOOOOOOOOOOOOOOOOOOOOOOOOOOOOOOOOOOOOOOOOOOOOOOOOOOOOOOOOOOOOOOOOOOO | OOOOOOOOOOOOOOOOOOOOOOOOOOOOOOOOOOOOOOOOOOOOOOOOOOOOOOOOOOOOOOOOOOOOOOOOOOOOOOOOOOOOOOOOOO | OOOOOOOOOOOOOOOOOOOOOOOOOOOOOOOOOOOOOOOOOOOOOOOOOOOOOOOOOOOOOOOOOOOOOOOOOOOOOOOOOOOOOOOOOO |
| Second Source Change |  |  |  |  |  |  |  |  |  |
| Item | Location | Change Type | Foxconn P/N | Part Description | Manufacturer Full Name | Manufacturer P/N | RoHS | Sheet |  |
| OOOOOOOOOOOOOOOOOOOOOOOOOOOOOOOOOOOOOOOOOOOOOOOOOOOOOOOOOOOOOOOOOOOOOOOOOOOOOOOOOOOOOOOOOO | OOOOOOOOOOOOOOOOOOOOOOOOOOOOOOOOOOOOOOOOOOOOOOOOOOOOOOOOOOOOOOOOOOOOOOOOOOOOOOOOOOOOOOOOOO | OOOOOOOOOOOOOOOOOOOOOOOOOOOOOOOOOOOOOOOOOOOOOOOOOOOOOOOOOOOOOOOOOOOOOOOOOOOOOOOOOOOOOOOOOO | OOOOOOOOOOOOOOOOOOOOOOOOOOOOOOOOOOOOOOOOOOOOOOOOOOOOOOOOOOOOOOOOOOOOOOOOOOOOOOOOOOOOOOOOOO | OOOOOOOOOOOOOOOOOOOOOOOOOOOOOOOOOOOOOOOOOOOOOOOOOOOOOOOOOOOOOOOOOOOOOOOOOOOOOOOOOOOOOOOOOO | OOOOOOOOOOOOOOOOOOOOOOOOOOOOOOOOOOOOOOOOOOOOOOOOOOOOOOOOOOOOOOOOOOOOOOOOOOOOOOOOOOOOOOOOOO | OOOOOOOOOOOOOOOOOOOOOOOOOOOOOOOOOOOOOOOOOOOOOOOOOOOOOOOOOOOOOOOOOOOOOOOOOOOOOOOOOOOOOOOOOO | OOOOOOOOOOOOOOOOOOOOOOOOOOOOOOOOOOOOOOOOOOOOOOOOOOOOOOOOOOOOOOOOOOOOOOOOOOOOOOOOOOOOOOOOOO | OOOOOOOOOOOOOOOOOOOOOOOOOOOOOOOOOOOOOOOOOOOOOOOOOOOOOOOOOOOOOOOOOOOOOOOOOOOOOOOOOOOOOOOOOO | OOOOOOOOOOOOOOOOOOOOOOOOOOOOOOOOOOOOOOOOOOOOOOOOOOOOOOOOOOOOOOOOOOOOOOOOOOOOOOOOOOOOOOOOOO |
| Master Materials Change |  |  |  |  |  |  |  |  |  |
| Item | Foxconn P/N | Orig._Usage | New_Usage | Part Description | Manufacturer Full Name | Manufacturer P/N | RoHS | Location | Sheet |
| 1 | 610113D00-017-G | 0 | 1 | RES,10.5KOhm,+/-1%,1/16W,G,SMD0402 | KOA SPEER ELECTRONICS, INC. | RK73H1ETTP1052F | G | (+)PHAR35 | PWA BOM |
|  | 610113D00-011-G |  |  | RES,10.5KOhm,+/-1%,1/16W,G,SMD0402 | YAGEO CORPORATION COMPONENT | RC0402FR-0710K5L |  |  | PWA BOM |
|  | 610113D00-012-G |  |  | RES,10.5KOhm,+/-1%,1/16W,G,SMD0402 | WALSIN TECHNOLOGY CORPORATION | WR04X1052FTL |  |  | PWA BOM |
|  | 610113D00-044-G |  |  | RES,10.5KOhm,+/-1%,1/16W,G,SMD0402 | TA-I TECHNOLOGY CO., LTD. | RM04FTN1052 |  |  | PWA BOM |
| 2 | 61011PE00-017-G | 1 | 0 | RES,8.87KOhm,+/-1%,1/16W,G,SMD0402 | KOA SPEER ELECTRONICS, INC. | RK73H1ETTP8871F | G | (-)PHAR35 | PWA BOM |
|  | 61011PE00-012-G |  |  | RES,8.87KOhm,+/-1%,1/16W,G,SMD0402 | WALSIN TECHNOLOGY CORPORATION | WR04X8871FTL |  |  | PWA BOM |
|  | 61011PE00-011-G |  |  | RES,8.87KOhm,+/-1%,1/16W,G,SMD0402 | YAGEO CORPORATION COMPONENT | RC0402FR-078K87L |  |  | PWA BOM |
|  | 61011PE00-044-G |  |  | RES,8.87KOhm,+/-1%,1/16W,G,SMD0402 | TA-I TECHNOLOGY CO., LTD. | RM04FTN8871 |  |  | PWA BOM |
| OOOOOOOOOOOOOOOOOOOOOOOOOOOOOOOOOOOOOOOOOOOOOOOOOOOOOOOOOOOOOOOOOOOOOOOOOOOOOOOOOOOOOOOOOO | OOOOOOOOOOOOOOOOOOOOOOOOOOOOOOOOOOOOOOOOOOOOOOOOOOOOOOOOOOOOOOOOOOOOOOOOOOOOOOOOOOOOOOOOOO | OOOOOOOOOOOOOOOOOOOOOOOOOOOOOOOOOOOOOOOOOOOOOOOOOOOOOOOOOOOOOOOOOOOOOOOOOOOOOOOOOOOOOOOOOO | OOOOOOOOOOOOOOOOOOOOOOOOOOOOOOOOOOOOOOOOOOOOOOOOOOOOOOOOOOOOOOOOOOOOOOOOOOOOOOOOOOOOOOOOOO | OOOOOOOOOOOOOOOOOOOOOOOOOOOOOOOOOOOOOOOOOOOOOOOOOOOOOOOOOOOOOOOOOOOOOOOOOOOOOOOOOOOOOOOOOO | OOOOOOOOOOOOOOOOOOOOOOOOOOOOOOOOOOOOOOOOOOOOOOOOOOOOOOOOOOOOOOOOOOOOOOOOOOOOOOOOOOOOOOOOOO | OOOOOOOOOOOOOOOOOOOOOOOOOOOOOOOOOOOOOOOOOOOOOOOOOOOOOOOOOOOOOOOOOOOOOOOOOOOOOOOOOOOOOOOOOO | OOOOOOOOOOOOOOOOOOOOOOOOOOOOOOOOOOOOOOOOOOOOOOOOOOOOOOOOOOOOOOOOOOOOOOOOOOOOOOOOOOOOOOOOOO | OOOOOOOOOOOOOOOOOOOOOOOOOOOOOOOOOOOOOOOOOOOOOOOOOOOOOOOOOOOOOOOOOOOOOOOOOOOOOOOOOOOOOOOOOO |  |
| TLA Parts Change |  |  |  |  |  |  |  |  |  |
| Item | Foxconn P/N | Qty | Part Description | Manufacturer Full Name | Manufacturer P/N | RoHS | Location | Remark |  |
| BOM Change List Date:Tue Nov 21 10:54:26 GMT+08:00 2017 |  |  |  |  |  |  |  |  |  |
| New BOM file : E:\barreleye g2\1120\foxbis\FPDB 1121.xls |  |  |  |  |  |  |  |  |  |
| Old BOM file : E:\barreleye g2\1120\foxbis\FPDB 0922.xls |  |  |  |  |  |  |  |  |  |
| ##### Add Parts |  |  |  |  |  |  |  |  |  |
| Item | Location | Qty | Foxconn P/N | Part Description | Manufacturer Full Name | Manufacturer P/N | RoHS | Sheet |  |
| 1 | R1827 | 1 | 610107A00-017-G | RES,0 Ohm,+/-5%,1/16W,G,SMD0402 | KOA SPEER ELECTRONICS, INC. | RK73Z1ETTP | G | PWA BOM |  |
|  |  |  | 610107A00-012-G | RES,0 Ohm,+/-5%,1/16W,G,SMD0402 | WALSIN TECHNOLOGY CORPORATION | WR04X000PTL | G | PWA BOM |  |
|  |  |  | 610107A00-011-G | RES,0 Ohm,+/-5%,1/16W,G,SMD0402 | YAGEO CORPORATION COMPONENT | RC0402JR-070RL | G | PWA BOM |  |
|  |  |  | 610107A00-044-G | RES,0 Ohm,+/-5%,1/16W,G,SMD0402 | TA-I TECHNOLOGY CO., LTD. | RM04JTN0 | G | PWA BOM |  |
|  |  |  | 610107A00-024-G | RES,0 Ohm,+/-5%,1/16W,G,SMD0402 | PANASONIC INDUSTRIAL CO.,LTD. | ERJ2GE0R00X | G | PWA BOM |  |
|  |  |  | 610107A00-029-G | RES,0 Ohm,+/-5%,1/16W,G,SMD0402 | VISHAY ENTER TECHNO LOGY.INC | CRCW04020000Z0ED | G | PWA BOM |  |
| ##### Remove Parts |  |  |  |  |  |  |  |  |  |
| Item | Location | Qty | Foxconn P/N | Part Description | Manufacturer Full Name | Manufacturer P/N | RoHS | Sheet |  |
| 1 | R235 | 1 | 610107A00-017-G | RES,0 Ohm,+/-5%,1/16W,G,SMD0402 | KOA SPEER ELECTRONICS, INC. | RK73Z1ETTP | G | PWA BOM |  |
|  |  |  | 610107A00-012-G | RES,0 Ohm,+/-5%,1/16W,G,SMD0402 | WALSIN TECHNOLOGY CORPORATION | WR04X000PTL | G | PWA BOM |  |
|  |  |  | 610107A00-011-G | RES,0 Ohm,+/-5%,1/16W,G,SMD0402 | YAGEO CORPORATION COMPONENT | RC0402JR-070RL | G | PWA BOM |  |
|  |  |  | 610107A00-044-G | RES,0 Ohm,+/-5%,1/16W,G,SMD0402 | TA-I TECHNOLOGY CO., LTD. | RM04JTN0 | G | PWA BOM |  |
|  |  |  | 610107A00-024-G | RES,0 Ohm,+/-5%,1/16W,G,SMD0402 | PANASONIC INDUSTRIAL CO.,LTD. | ERJ2GE0R00X | G | PWA BOM |  |
|  |  |  | 610107A00-029-G | RES,0 Ohm,+/-5%,1/16W,G,SMD0402 | VISHAY ENTER TECHNO LOGY.INC | CRCW04020000Z0ED | G | PWA BOM |  |
| ##### Change Parts |  |  |  |  |  |  |  |  |  |
| Item | Location | Qty | Foxconn P/N | Part Description | Manufacturer Full Name | Manufacturer P/N | RoHS | Sheet | Remark |
| 1 | PSRR19 | 1 | 61100YB00-017-G | RES,2.94KOhm,+/-0.1%,1/16W,G,SMD0402 | KOA SPEER ELECTRONICS, INC. | RN731ETTP2941B25 | G | PWA BOM | In New BOM |
|  |  |  | 61100YB00-011-G | RES,2.94KOhm,+/-0.1%,1/16W,G,SMD0402 | YAGEO CORPORATION COMPONENT | RT0402BRD072K94L |  | PWA BOM | In New BOM |
|  |  |  | 61100YB00-044-G | RES,2.94KOhm,+/-0.1%,1/16W,G,SMD0402 | TA-I TECHNOLOGY CO., LTD | RB04BTP2941 |  | PWA BOM | In New BOM |
|  | PSRR19 | 1 | 61100YB00-017-G | RES,2.94KOhm,+/-0.1%,1/16W,G,SMD0402 | KOA SPEER ELECTRONICS, INC. | RN731ETTP2941B25 | G | PWA BOM | In Old BOM |
| 2 | R1492 | 1 | 610118800-017-G | RES,499KOhm,+/-1%,1/8W,G,SMD0805 | KOA SPEER ELECTRONICS, INC. | RK73H2ATTD4993F | G | PWA BOM | In New BOM |
|  |  |  | 610118800-024-G | RES,499KOhm,+/-1%,1/8W,G,SMD0805 | PANASONIC INDUSTRIAL CO.,LTD. | ERJ6ENF4993V | G | PWA BOM | In New BOM |
|  |  |  | 610118800-011-G | RES,499KOhm,+/-1%,1/8W,G,SMD0805 | YAGEO CORPORATION COMPONENT | RC0805FR-07499KL | G | PWA BOM | In New BOM |
|  | R1492 | 1 | 610118800-017-G | RES,499KOhm,+/-1%,1/8W,G,SMD0805 | KOA SPEER ELECTRONICS, INC. | RK73H2ATTD4993F | G | PWA BOM | In Old BOM |
|  |  |  | 610118800-024-G | RES,499KOhm,+/-1%,1/8W,G,SMD0805 | PANASONIC INDUSTRIAL CO.,LTD. | ERJ6ENF4993V | G | PWA BOM | In Old BOM |
|  |  |  | RC0805FR-07499KL | RES,499KOhm,+/-1%,1/8W,G,SMD0805 | YAGEO CORPORATION COMPONENT | RC0805FR-07499KL | G | PWA BOM | In Old BOM |
| ##### Change Revision |  |  |  |  |  |  |  |  |  |
| Sheet | REV OF BOM | CUSTOMER | CUSTOMER P/N | PWA PN | PWA DESCRIPTION | PWA REV | DATE | Remark |  |
| OOOOOOOOOOOOOOOOOOOOOOOOOOOOOOOOOOOOOOOOOOOOOOOOOOOOOOOOOOOOOOOOOOOOOOOOOOOOOOOOOOOOOOOOOO | OOOOOOOOOOOOOOOOOOOOOOOOOOOOOOOOOOOOOOOOOOOOOOOOOOOOOOOOOOOOOOOOOOOOOOOOOOOOOOOOOOOOOOOOOO | OOOOOOOOOOOOOOOOOOOOOOOOOOOOOOOOOOOOOOOOOOOOOOOOOOOOOOOOOOOOOOOOOOOOOOOOOOOOOOOOOOOOOOOOOO | OOOOOOOOOOOOOOOOOOOOOOOOOOOOOOOOOOOOOOOOOOOOOOOOOOOOOOOOOOOOOOOOOOOOOOOOOOOOOOOOOOOOOOOOOO | OOOOOOOOOOOOOOOOOOOOOOOOOOOOOOOOOOOOOOOOOOOOOOOOOOOOOOOOOOOOOOOOOOOOOOOOOOOOOOOOOOOOOOOOOO | OOOOOOOOOOOOOOOOOOOOOOOOOOOOOOOOOOOOOOOOOOOOOOOOOOOOOOOOOOOOOOOOOOOOOOOOOOOOOOOOOOOOOOOOOO | OOOOOOOOOOOOOOOOOOOOOOOOOOOOOOOOOOOOOOOOOOOOOOOOOOOOOOOOOOOOOOOOOOOOOOOOOOOOOOOOOOOOOOOOOO | OOOOOOOOOOOOOOOOOOOOOOOOOOOOOOOOOOOOOOOOOOOOOOOOOOOOOOOOOOOOOOOOOOOOOOOOOOOOOOOOOOOOOOOOOO | OOOOOOOOOOOOOOOOOOOOOOOOOOOOOOOOOOOOOOOOOOOOOOOOOOOOOOOOOOOOOOOOOOOOOOOOOOOOOOOOOOOOOOOOOO | OOOOOOOOOOOOOOOOOOOOOOOOOOOOOOOOOOOOOOOOOOOOOOOOOOOOOOOOOOOOOOOOOOOOOOOOOOOOOOOOOOOOOOOOOO |
| Second Source Change |  |  |  |  |  |  |  |  |  |
| Item | Location | Change Type | Foxconn P/N | Part Description | Manufacturer Full Name | Manufacturer P/N | RoHS | Sheet |  |
| 1 | PSRR19 |  | 61100YB00-017-G | RES,2.94KOhm,+/-0.1%,1/16W,G,SMD0402 | KOA SPEER ELECTRONICS, INC. | RN731ETTP2941B25 | G | PWA BOM |  |
|  |  | ADD | 61100YB00-011-G | RES,2.94KOhm,+/-0.1%,1/16W,G,SMD0402 | YAGEO CORPORATION COMPONENT | RT0402BRD072K94L |  | PWA BOM |  |
|  |  | ADD | 61100YB00-044-G | RES,2.94KOhm,+/-0.1%,1/16W,G,SMD0402 | TA-I TECHNOLOGY CO., LTD | RB04BTP2941 |  | PWA BOM |  |
| 2 | R1492 |  | 610118800-017-G | RES,499KOhm,+/-1%,1/8W,G,SMD0805 | KOA SPEER ELECTRONICS, INC. | RK73H2ATTD4993F | G | PWA BOM |  |
|  |  | NO | 610118800-024-G | RES,499KOhm,+/-1%,1/8W,G,SMD0805 | PANASONIC INDUSTRIAL CO.,LTD. | ERJ6ENF4993V | G | PWA BOM |  |
|  |  | ADD | 610118800-011-G | RES,499KOhm,+/-1%,1/8W,G,SMD0805 | YAGEO CORPORATION COMPONENT | RC0805FR-07499KL | G | PWA BOM |  |
|  |  | Delete | RC0805FR-07499KL | RES,499KOhm,+/-1%,1/8W,G,SMD0805 | YAGEO CORPORATION COMPONENT | RC0805FR-07499KL | G | PWA BOM |  |
| OOOOOOOOOOOOOOOOOOOOOOOOOOOOOOOOOOOOOOOOOOOOOOOOOOOOOOOOOOOOOOOOOOOOOOOOOOOOOOOOOOOOOOOOOO | OOOOOOOOOOOOOOOOOOOOOOOOOOOOOOOOOOOOOOOOOOOOOOOOOOOOOOOOOOOOOOOOOOOOOOOOOOOOOOOOOOOOOOOOOO | OOOOOOOOOOOOOOOOOOOOOOOOOOOOOOOOOOOOOOOOOOOOOOOOOOOOOOOOOOOOOOOOOOOOOOOOOOOOOOOOOOOOOOOOOO | OOOOOOOOOOOOOOOOOOOOOOOOOOOOOOOOOOOOOOOOOOOOOOOOOOOOOOOOOOOOOOOOOOOOOOOOOOOOOOOOOOOOOOOOOO | OOOOOOOOOOOOOOOOOOOOOOOOOOOOOOOOOOOOOOOOOOOOOOOOOOOOOOOOOOOOOOOOOOOOOOOOOOOOOOOOOOOOOOOOOO | OOOOOOOOOOOOOOOOOOOOOOOOOOOOOOOOOOOOOOOOOOOOOOOOOOOOOOOOOOOOOOOOOOOOOOOOOOOOOOOOOOOOOOOOOO | OOOOOOOOOOOOOOOOOOOOOOOOOOOOOOOOOOOOOOOOOOOOOOOOOOOOOOOOOOOOOOOOOOOOOOOOOOOOOOOOOOOOOOOOOO | OOOOOOOOOOOOOOOOOOOOOOOOOOOOOOOOOOOOOOOOOOOOOOOOOOOOOOOOOOOOOOOOOOOOOOOOOOOOOOOOOOOOOOOOOO | OOOOOOOOOOOOOOOOOOOOOOOOOOOOOOOOOOOOOOOOOOOOOOOOOOOOOOOOOOOOOOOOOOOOOOOOOOOOOOOOOOOOOOOOOO | OOOOOOOOOOOOOOOOOOOOOOOOOOOOOOOOOOOOOOOOOOOOOOOOOOOOOOOOOOOOOOOOOOOOOOOOOOOOOOOOOOOOOOOOOO |
| Master Materials Change |  |  |  |  |  |  |  |  |  |
| Item | Foxconn P/N | Orig._Usage | New_Usage | Part Description | Manufacturer Full Name | Manufacturer P/N | RoHS | Location | Sheet |
| OOOOOOOOOOOOOOOOOOOOOOOOOOOOOOOOOOOOOOOOOOOOOOOOOOOOOOOOOOOOOOOOOOOOOOOOOOOOOOOOOOOOOOOOOO | OOOOOOOOOOOOOOOOOOOOOOOOOOOOOOOOOOOOOOOOOOOOOOOOOOOOOOOOOOOOOOOOOOOOOOOOOOOOOOOOOOOOOOOOOO | OOOOOOOOOOOOOOOOOOOOOOOOOOOOOOOOOOOOOOOOOOOOOOOOOOOOOOOOOOOOOOOOOOOOOOOOOOOOOOOOOOOOOOOOOO | OOOOOOOOOOOOOOOOOOOOOOOOOOOOOOOOOOOOOOOOOOOOOOOOOOOOOOOOOOOOOOOOOOOOOOOOOOOOOOOOOOOOOOOOOO | OOOOOOOOOOOOOOOOOOOOOOOOOOOOOOOOOOOOOOOOOOOOOOOOOOOOOOOOOOOOOOOOOOOOOOOOOOOOOOOOOOOOOOOOOO | OOOOOOOOOOOOOOOOOOOOOOOOOOOOOOOOOOOOOOOOOOOOOOOOOOOOOOOOOOOOOOOOOOOOOOOOOOOOOOOOOOOOOOOOOO | OOOOOOOOOOOOOOOOOOOOOOOOOOOOOOOOOOOOOOOOOOOOOOOOOOOOOOOOOOOOOOOOOOOOOOOOOOOOOOOOOOOOOOOOOO | OOOOOOOOOOOOOOOOOOOOOOOOOOOOOOOOOOOOOOOOOOOOOOOOOOOOOOOOOOOOOOOOOOOOOOOOOOOOOOOOOOOOOOOOOO | OOOOOOOOOOOOOOOOOOOOOOOOOOOOOOOOOOOOOOOOOOOOOOOOOOOOOOOOOOOOOOOOOOOOOOOOOOOOOOOOOOOOOOOOOO | OOOOOOOOOOOOOOOOOOOOOOOOOOOOOOOOOOOOOOOOOOOOOOOOOOOOOOOOOOOOOOOOOOOOOOOOOOOOOOOOOOOOOOOOOO |
| TLA Parts Change |  |  |  |  |  |  |  |  |  |
| Item | Foxconn P/N | Qty | Part Description | Manufacturer Full Name | Manufacturer P/N | RoHS | Location | Remark | BOM |
| BOM Change List Date:Thu Nov 23 16:07:56 GMT+08:00 2017 |  |  |  |  |  |  |  |  |  |
| New BOM file : E:\barreleye g2\1123\FPDB 1123.xls |  |  |  |  |  |  |  |  |  |
| Old BOM file : E:\barreleye g2\1123\FPDB 1121.xls |  |  |  |  |  |  |  |  |  |
| ##### Add Parts |  |  |  |  |  |  |  |  |  |
| Item | Location | Qty | Foxconn P/N | Part Description | Manufacturer Full Name | Manufacturer P/N | RoHS | Sheet |  |
| ##### Remove Parts |  |  |  |  |  |  |  |  |  |
| Item | Location | Qty | Foxconn P/N | Part Description | Manufacturer Full Name | Manufacturer P/N | RoHS | Sheet |  |
| ##### Change Parts |  |  |  |  |  |  |  |  |  |
| Item | Location | Qty | Foxconn P/N | Part Description | Manufacturer Full Name | Manufacturer P/N | RoHS | Sheet | Remark |
| 1 | PHAR1 | 1 | 610601801-32D-G | RES,0.5mOhm,+/-1%,2W,G,SMD1225 | Thin Film Technology Corporation | CPA1225R0M50FW-T5 | G | PWA BOM | In New BOM |
|  | PHAR1 | 1 | 610601800-32D-G | RES,0.5mOhm,+/-1%,2W,G,SMD1225 | Thin Film Technology Corporation | CPA1225R0M50FW-T50 | G | PWA BOM | In Old BOM |
| ##### Change Revision |  |  |  |  |  |  |  |  |  |
| Sheet | REV OF BOM | CUSTOMER | CUSTOMER P/N | PWA PN | PWA DESCRIPTION | PWA REV | DATE | Remark |  |
| OOOOOOOOOOOOOOOOOOOOOOOOOOOOOOOOOOOOOOOOOOOOOOOOOOOOOOOOOOOOOOOOOOOOOOOOOOOOOOOOOOOOOOOOOO | OOOOOOOOOOOOOOOOOOOOOOOOOOOOOOOOOOOOOOOOOOOOOOOOOOOOOOOOOOOOOOOOOOOOOOOOOOOOOOOOOOOOOOOOOO | OOOOOOOOOOOOOOOOOOOOOOOOOOOOOOOOOOOOOOOOOOOOOOOOOOOOOOOOOOOOOOOOOOOOOOOOOOOOOOOOOOOOOOOOOO | OOOOOOOOOOOOOOOOOOOOOOOOOOOOOOOOOOOOOOOOOOOOOOOOOOOOOOOOOOOOOOOOOOOOOOOOOOOOOOOOOOOOOOOOOO | OOOOOOOOOOOOOOOOOOOOOOOOOOOOOOOOOOOOOOOOOOOOOOOOOOOOOOOOOOOOOOOOOOOOOOOOOOOOOOOOOOOOOOOOOO | OOOOOOOOOOOOOOOOOOOOOOOOOOOOOOOOOOOOOOOOOOOOOOOOOOOOOOOOOOOOOOOOOOOOOOOOOOOOOOOOOOOOOOOOOO | OOOOOOOOOOOOOOOOOOOOOOOOOOOOOOOOOOOOOOOOOOOOOOOOOOOOOOOOOOOOOOOOOOOOOOOOOOOOOOOOOOOOOOOOOO | OOOOOOOOOOOOOOOOOOOOOOOOOOOOOOOOOOOOOOOOOOOOOOOOOOOOOOOOOOOOOOOOOOOOOOOOOOOOOOOOOOOOOOOOOO | OOOOOOOOOOOOOOOOOOOOOOOOOOOOOOOOOOOOOOOOOOOOOOOOOOOOOOOOOOOOOOOOOOOOOOOOOOOOOOOOOOOOOOOOOO | OOOOOOOOOOOOOOOOOOOOOOOOOOOOOOOOOOOOOOOOOOOOOOOOOOOOOOOOOOOOOOOOOOOOOOOOOOOOOOOOOOOOOOOOOO |
| Second Source Change |  |  |  |  |  |  |  |  |  |
| Item | Location | Change Type | Foxconn P/N | Part Description | Manufacturer Full Name | Manufacturer P/N | RoHS | Sheet |  |
| OOOOOOOOOOOOOOOOOOOOOOOOOOOOOOOOOOOOOOOOOOOOOOOOOOOOOOOOOOOOOOOOOOOOOOOOOOOOOOOOOOOOOOOOOO | OOOOOOOOOOOOOOOOOOOOOOOOOOOOOOOOOOOOOOOOOOOOOOOOOOOOOOOOOOOOOOOOOOOOOOOOOOOOOOOOOOOOOOOOOO | OOOOOOOOOOOOOOOOOOOOOOOOOOOOOOOOOOOOOOOOOOOOOOOOOOOOOOOOOOOOOOOOOOOOOOOOOOOOOOOOOOOOOOOOOO | OOOOOOOOOOOOOOOOOOOOOOOOOOOOOOOOOOOOOOOOOOOOOOOOOOOOOOOOOOOOOOOOOOOOOOOOOOOOOOOOOOOOOOOOOO | OOOOOOOOOOOOOOOOOOOOOOOOOOOOOOOOOOOOOOOOOOOOOOOOOOOOOOOOOOOOOOOOOOOOOOOOOOOOOOOOOOOOOOOOOO | OOOOOOOOOOOOOOOOOOOOOOOOOOOOOOOOOOOOOOOOOOOOOOOOOOOOOOOOOOOOOOOOOOOOOOOOOOOOOOOOOOOOOOOOOO | OOOOOOOOOOOOOOOOOOOOOOOOOOOOOOOOOOOOOOOOOOOOOOOOOOOOOOOOOOOOOOOOOOOOOOOOOOOOOOOOOOOOOOOOOO | OOOOOOOOOOOOOOOOOOOOOOOOOOOOOOOOOOOOOOOOOOOOOOOOOOOOOOOOOOOOOOOOOOOOOOOOOOOOOOOOOOOOOOOOOO | OOOOOOOOOOOOOOOOOOOOOOOOOOOOOOOOOOOOOOOOOOOOOOOOOOOOOOOOOOOOOOOOOOOOOOOOOOOOOOOOOOOOOOOOOO | OOOOOOOOOOOOOOOOOOOOOOOOOOOOOOOOOOOOOOOOOOOOOOOOOOOOOOOOOOOOOOOOOOOOOOOOOOOOOOOOOOOOOOOOOO |
| Master Materials Change |  |  |  |  |  |  |  |  |  |
| Item | Foxconn P/N | Orig._Usage | New_Usage | Part Description | Manufacturer Full Name | Manufacturer P/N | RoHS | Location | Sheet |
| 1 | 610601801-32D-G | 0 | 1 | RES,0.5mOhm,+/-1%,2W,G,SMD1225 | Thin Film Technology Corporation | CPA1225R0M50FW-T5 | G | (+)PHAR1 | PWA BOM |
| 2 | 610601800-32D-G | 1 | 0 | RES,0.5mOhm,+/-1%,2W,G,SMD1225 | Thin Film Technology Corporation | CPA1225R0M50FW-T50 | G | (-)PHAR1 | PWA BOM |
| OOOOOOOOOOOOOOOOOOOOOOOOOOOOOOOOOOOOOOOOOOOOOOOOOOOOOOOOOOOOOOOOOOOOOOOOOOOOOOOOOOOOOOOOOO | OOOOOOOOOOOOOOOOOOOOOOOOOOOOOOOOOOOOOOOOOOOOOOOOOOOOOOOOOOOOOOOOOOOOOOOOOOOOOOOOOOOOOOOOOO | OOOOOOOOOOOOOOOOOOOOOOOOOOOOOOOOOOOOOOOOOOOOOOOOOOOOOOOOOOOOOOOOOOOOOOOOOOOOOOOOOOOOOOOOOO | OOOOOOOOOOOOOOOOOOOOOOOOOOOOOOOOOOOOOOOOOOOOOOOOOOOOOOOOOOOOOOOOOOOOOOOOOOOOOOOOOOOOOOOOOO | OOOOOOOOOOOOOOOOOOOOOOOOOOOOOOOOOOOOOOOOOOOOOOOOOOOOOOOOOOOOOOOOOOOOOOOOOOOOOOOOOOOOOOOOOO | OOOOOOOOOOOOOOOOOOOOOOOOOOOOOOOOOOOOOOOOOOOOOOOOOOOOOOOOOOOOOOOOOOOOOOOOOOOOOOOOOOOOOOOOOO | OOOOOOOOOOOOOOOOOOOOOOOOOOOOOOOOOOOOOOOOOOOOOOOOOOOOOOOOOOOOOOOOOOOOOOOOOOOOOOOOOOOOOOOOOO | OOOOOOOOOOOOOOOOOOOOOOOOOOOOOOOOOOOOOOOOOOOOOOOOOOOOOOOOOOOOOOOOOOOOOOOOOOOOOOOOOOOOOOOOOO | OOOOOOOOOOOOOOOOOOOOOOOOOOOOOOOOOOOOOOOOOOOOOOOOOOOOOOOOOOOOOOOOOOOOOOOOOOOOOOOOOOOOOOOOOO | OOOOOOOOOOOOOOOOOOOOOOOOOOOOOOOOOOOOOOOOOOOOOOOOOOOOOOOOOOOOOOOOOOOOOOOOOOOOOOOOOOOOOOOOOO |
| TLA Parts Change |  |  |  |  |  |  |  |  |  |
| Item | Foxconn P/N | Qty | Part Description | Manufacturer Full Name | Manufacturer P/N | RoHS | Location | Remark | BOM |
